G04 ================== begin FILE IDENTIFICATION RECORD ==================*
G04 Layout Name:  15669-1.brd*
G04 Film Name:    L3*
G04 File Format:  Gerber RS274X*
G04 File Origin:  Cadence Allegro 16.5-S056*
G04 Origin Date:  Wed Nov 16 04:08:42 2016*
G04 *
G04 Layer:  VIA CLASS/L3*
G04 Layer:  PIN/L3*
G04 Layer:  ETCH/L3*
G04 Layer:  DRAWING FORMAT/LAYER_PCB_STORY*
G04 Layer:  DRAWING FORMAT/LAYER_L3*
G04 *
G04 Offset:    (0.00 0.00)*
G04 Mirror:    No*
G04 Mode:      Positive*
G04 Rotation:  0*
G04 FullContactRelief:  No*
G04 UndefLineWidth:     6.00*
G04 ================== end FILE IDENTIFICATION RECORD ====================*
%FSLAX35Y35*MOIN*%
%IR0*IPPOS*OFA0.00000B0.00000*MIA0B0*SFA1.00000B1.00000*%
%ADD10C,.02*%
%ADD12C,.022*%
%ADD11C,.028*%
%ADD13C,.04*%
%ADD14C,.006*%
%ADD15C,.0065*%
%ADD19O,.12702X.08402*%
%ADD18C,.04404*%
%ADD20C,.04604*%
%ADD17C,.09704*%
%ADD16C,.11104*%
G75*
%LPD*%
G75*
G36*
G01X28904Y739378D02*
G03X27419Y735351I-1205J-1843D01*
G02X27707Y734742I-51J-397D01*
G02X19439Y729030I-10778J6762D01*
G01X18000D01*
Y724421D01*
X17999Y724411D01*
G03X17988Y724206I2001J-210D01*
G01Y721006D01*
G03X17999Y720801I2012J5D01*
G01X18000Y720791D01*
Y711822D01*
X17999Y711812D01*
G03X17988Y711607I2001J-210D01*
G01Y708407D01*
G03X17999Y708202I2012J5D01*
G01X18000Y708192D01*
Y699224D01*
X17999Y699214D01*
G03X17988Y699009I2001J-210D01*
G01Y695809D01*
G03X17999Y695604I2012J5D01*
G01X18000Y695594D01*
Y686625D01*
X17999Y686615D01*
G03X17988Y686410I2001J-210D01*
G01Y683210D01*
G03X17999Y683005I2012J5D01*
G01X18000Y682995D01*
Y674027D01*
X17999Y674017D01*
G03X17988Y673812I2001J-210D01*
G01Y670612D01*
G03X17999Y670407I2012J5D01*
G01X18000Y670397D01*
Y661428D01*
X17999Y661418D01*
G03X17988Y661213I2001J-210D01*
G01Y658013D01*
G03X17999Y657808I2012J5D01*
G01X18000Y657798D01*
Y648830D01*
X17999Y648820D01*
G03X17988Y648615I2001J-210D01*
G01Y645415D01*
G03X17999Y645210I2012J5D01*
G01X18000Y645200D01*
Y636232D01*
X17999Y636222D01*
G03X17988Y636017I2001J-210D01*
G01Y632817D01*
G03X17999Y632612I2012J5D01*
G01X18000Y632602D01*
Y623633D01*
X17999Y623623D01*
G03X17988Y623418I2001J-210D01*
G01Y620218D01*
G03X17999Y620013I2012J5D01*
G01X18000Y620003D01*
Y611035D01*
X17999Y611025D01*
G03X17988Y610820I2001J-210D01*
G01Y607620D01*
G03X17999Y607415I2012J5D01*
G01X18000Y607405D01*
Y592000D01*
X8000Y582000D01*
Y575463D01*
G03Y567389I3811J-4037D01*
G01Y8000D01*
X119262D01*
Y3004D01*
X3937D01*
G02X3004Y3937I0J933D01*
G01Y596998D01*
X13760D01*
Y733776D01*
X16929D01*
G03Y749232I0J7728D01*
G01X13760D01*
Y924002D01*
X3004D01*
Y1092998D01*
X13760D01*
Y1229839D01*
X16929D01*
G03Y1245295I0J7728D01*
G01X13760D01*
Y1420002D01*
X3004D01*
Y1510498D01*
X13760D01*
Y1647161D01*
X16929D01*
G03Y1662618I0J7728D01*
G01X13760D01*
Y1817708D01*
X14052Y1818000D01*
X25970D01*
X29558Y1814412D01*
X38887D01*
X40227Y1813072D01*
Y1804432D01*
X17500Y1781705D01*
Y1667601D01*
G02X17988Y1667570I-563J-12712D01*
G01Y1665887D01*
G03X21866Y1665137I2012J0D01*
G01X21917Y1665262D01*
X24299D01*
G02X24370Y1644567I-7370J-10373D01*
G01X24090Y1644518D01*
X21916D01*
X21865Y1644643D01*
G03X17988Y1643890I-1865J-753D01*
G01Y1640690D01*
G03X17999Y1640485I2012J5D01*
G01X18000Y1640475D01*
Y1631506D01*
X17999Y1631496D01*
G03X17988Y1631292I2001J-210D01*
G01Y1628091D01*
G03X17999Y1627886I2012J5D01*
G01X18000Y1627876D01*
Y1618908D01*
X17999Y1618898D01*
G03X17988Y1618694I2001J-210D01*
G01Y1615493D01*
G03X17999Y1615288I2012J5D01*
G01X18000Y1615278D01*
Y1606309D01*
X17999Y1606299D01*
G03X17988Y1606095I2001J-210D01*
G01Y1602894D01*
G03X17999Y1602689I2012J5D01*
G01X18000Y1602679D01*
Y1593711D01*
X17999Y1593701D01*
G03X17988Y1593497I2001J-210D01*
G01Y1590296D01*
G03X17999Y1590091I2012J5D01*
G01X18000Y1590081D01*
Y1571664D01*
X17999Y1571654D01*
G03X17988Y1571449I2001J-210D01*
G01Y1568249D01*
G03X17999Y1568044I2012J5D01*
G01X18000Y1568034D01*
Y1559065D01*
X17999Y1559055D01*
G03X17988Y1558850I2001J-210D01*
G01Y1555650D01*
G03X17999Y1555445I2012J5D01*
G01X18000Y1555435D01*
Y1546467D01*
X17999Y1546457D01*
G03X17988Y1546252I2001J-210D01*
G01Y1543052D01*
G03X17999Y1542847I2012J5D01*
G01X18000Y1542837D01*
Y1533869D01*
X17999Y1533859D01*
G03X17988Y1533654I2001J-210D01*
G01Y1530454D01*
G03X17999Y1530249I2012J5D01*
G01X18000Y1530239D01*
Y1412610D01*
X17999Y1412600D01*
G03X17988Y1412395I2001J-210D01*
G01Y1409195D01*
G03X17999Y1408990I2012J5D01*
G01X18000Y1408980D01*
Y1400011D01*
X17999Y1400001D01*
G03X17988Y1399796I2001J-210D01*
G01Y1396596D01*
G03X17999Y1396391I2012J5D01*
G01X18000Y1396381D01*
Y1387413D01*
X17999Y1387403D01*
G03X17988Y1387198I2001J-210D01*
G01Y1383998D01*
G03X17999Y1383793I2012J5D01*
G01X18000Y1383783D01*
Y1374814D01*
X17999Y1374804D01*
G03X17988Y1374599I2001J-210D01*
G01Y1371399D01*
G03X17999Y1371194I2012J5D01*
G01X18000Y1371184D01*
Y1362216D01*
X17999Y1362206D01*
G03X17988Y1362001I2001J-210D01*
G01Y1358801D01*
G03X17999Y1358596I2012J5D01*
G01X18000Y1358586D01*
Y1349617D01*
X17999Y1349607D01*
G03X17988Y1349402I2001J-210D01*
G01Y1346202D01*
G03X17999Y1345997I2012J5D01*
G01X18000Y1345987D01*
Y1337019D01*
X17999Y1337009D01*
G03X17988Y1336804I2001J-210D01*
G01Y1333604D01*
G03X17999Y1333399I2012J5D01*
G01X18000Y1333389D01*
Y1324421D01*
X17999Y1324411D01*
G03X17988Y1324206I2001J-210D01*
G01Y1321006D01*
G03X17999Y1320801I2012J5D01*
G01X18000Y1320791D01*
Y1302373D01*
X17999Y1302363D01*
G03X17988Y1302158I2001J-210D01*
G01Y1298958D01*
G03X17999Y1298753I2012J5D01*
G01X18000Y1298743D01*
Y1289775D01*
X17999Y1289765D01*
G03X17988Y1289560I2001J-210D01*
G01Y1286360D01*
G03X17999Y1286155I2012J5D01*
G01X18000Y1286145D01*
Y1277176D01*
X17999Y1277166D01*
G03X17988Y1276961I2001J-210D01*
G01Y1273761D01*
G03X17999Y1273556I2012J5D01*
G01X18000Y1273546D01*
Y1264578D01*
X17999Y1264568D01*
G03X17988Y1264363I2001J-210D01*
G01Y1261163D01*
G03X17999Y1260958I2012J5D01*
G01X18000Y1260948D01*
Y1251980D01*
X17999Y1251970D01*
G03X17988Y1251765I2001J-210D01*
G01Y1248565D01*
G03X21866Y1247814I2012J0D01*
G01X21917Y1247940D01*
X24300D01*
G02X18000Y1224888I-7370J-10373D01*
G01Y1220484D01*
X17999Y1220474D01*
G03X17988Y1220269I2001J-210D01*
G01Y1217069D01*
G03X17999Y1216864I2012J5D01*
G01X18000Y1216854D01*
Y1207885D01*
X17999Y1207875D01*
G03X17988Y1207670I2001J-210D01*
G01Y1204470D01*
G03X17999Y1204265I2012J5D01*
G01X18000Y1204255D01*
Y1195287D01*
X17999Y1195277D01*
G03X17988Y1195072I2001J-210D01*
G01Y1191872D01*
G03X17999Y1191667I2012J5D01*
G01X18000Y1191657D01*
Y1182688D01*
X17999Y1182678D01*
G03X17988Y1182473I2001J-210D01*
G01Y1179273D01*
G03X17999Y1179068I2012J5D01*
G01X18000Y1179058D01*
Y1170090D01*
X17999Y1170080D01*
G03X17988Y1169875I2001J-210D01*
G01Y1166675D01*
G03X17999Y1166470I2012J5D01*
G01X18000Y1166460D01*
Y1157491D01*
X17999Y1157481D01*
G03X17988Y1157276I2001J-210D01*
G01Y1154076D01*
G03X17999Y1153871I2012J5D01*
G01X18000Y1153861D01*
Y1144893D01*
X17999Y1144883D01*
G03X17988Y1144678I2001J-210D01*
G01Y1141478D01*
G03X17999Y1141273I2012J5D01*
G01X18000Y1141263D01*
Y1119696D01*
X17999Y1119686D01*
G03X17988Y1119481I2001J-210D01*
G01Y1116281D01*
G03X17999Y1116076I2012J5D01*
G01X18000Y1116066D01*
Y1107098D01*
X17999Y1107088D01*
G03X17988Y1106883I2001J-210D01*
G01Y1103683D01*
G03X17999Y1103478I2012J5D01*
G01X18000Y1103468D01*
Y1041724D01*
G03Y1017322I15469J-12201D01*
G01Y988500D01*
X22500Y984000D01*
Y934000D01*
X18000Y929500D01*
Y916547D01*
X17999Y916537D01*
G03X17988Y916332I2001J-210D01*
G01Y913132D01*
G03X17999Y912927I2012J5D01*
G01X18000Y912917D01*
Y903948D01*
X17999Y903938D01*
G03X17988Y903733I2001J-210D01*
G01Y900533D01*
G03X17999Y900328I2012J5D01*
G01X18000Y900318D01*
Y878751D01*
X17999Y878741D01*
G03X17988Y878536I2001J-210D01*
G01Y875336D01*
G03X17999Y875131I2012J5D01*
G01X18000Y875121D01*
Y866153D01*
X17999Y866143D01*
G03X17988Y865938I2001J-210D01*
G01Y862738D01*
G03X17999Y862533I2012J5D01*
G01X18000Y862523D01*
Y853554D01*
X17999Y853544D01*
G03X17988Y853339I2001J-210D01*
G01Y850139D01*
G03X17999Y849934I2012J5D01*
G01X18000Y849924D01*
Y840956D01*
X17999Y840946D01*
G03X17988Y840741I2001J-210D01*
G01Y837541D01*
G03X17999Y837336I2012J5D01*
G01X18000Y837326D01*
Y828358D01*
X17999Y828348D01*
G03X17988Y828143I2001J-210D01*
G01Y824943D01*
G03X17999Y824738I2012J5D01*
G01X18000Y824728D01*
Y815759D01*
X17999Y815749D01*
G03X17988Y815544I2001J-210D01*
G01Y812344D01*
G03X17999Y812139I2012J5D01*
G01X18000Y812129D01*
Y803161D01*
X17999Y803151D01*
G03X17988Y802946I2001J-210D01*
G01Y799746D01*
G03X17999Y799541I2012J5D01*
G01X18000Y799531D01*
Y790562D01*
X17999Y790552D01*
G03X17988Y790347I2001J-210D01*
G01Y787147D01*
G03X17999Y786942I2012J5D01*
G01X18000Y786932D01*
Y768515D01*
X17999Y768505D01*
G03X17988Y768300I2001J-210D01*
G01Y765100D01*
G03X17999Y764895I2012J5D01*
G01X18000Y764885D01*
Y755917D01*
X17999Y755907D01*
G03X17988Y755702I2001J-210D01*
G01Y752502D01*
G03X21866Y751751I2012J0D01*
G01X21917Y751876D01*
X24299D01*
G02X29518Y739655I-7370J-10372D01*
G02X28904Y739378I-396J58D01*
G37*
G36*
G01X17000Y1822300D02*
X13809Y1825491D01*
Y1838197D01*
X13414Y1838592D01*
X7131D01*
X6560Y1839162D01*
Y1856012D01*
X6947Y1856399D01*
X14124D01*
X17465Y1859740D01*
Y1865153D01*
X14144Y1868474D01*
X9962D01*
X9217Y1869219D01*
Y1877217D01*
X12938Y1880938D01*
X32027D01*
X32100Y1880865D01*
Y1822755D01*
X31645Y1822300D01*
X17000D01*
G37*
G36*
G01X1015228Y1675945D02*
G02X1020094Y1686309I13472J-1D01*
G03X1029402Y1700056I3134J7903D01*
G01Y1984126D01*
X8000D01*
Y1881771D01*
X5864Y1879636D01*
X3004D01*
Y1988189D01*
G02X3937Y1989122I933J0D01*
G01X1033465D01*
G02X1034398Y1988189I0J-933D01*
G01Y1686599D01*
X1032220Y1684421D01*
X1028700D01*
X1028690Y1684422D01*
G03X1020223Y1675955I-745J-7722D01*
G01X1020224Y1675945D01*
Y1621265D01*
X1018046Y1619087D01*
X993681D01*
G03Y1608866I0J-5110D01*
G01X1018046D01*
X1020224Y1606688D01*
Y1434285D01*
G03X1028694Y1425815I7967J-503D01*
G01X1032220D01*
X1034398Y1423637D01*
Y729030D01*
X1029402D01*
Y1410180D01*
G03X1020094Y1423927I-6174J5844D01*
G02X1015228Y1434291I8606J10365D01*
G01Y1603870D01*
X993681D01*
G02Y1624083I0J10106D01*
G01X1015228D01*
Y1675945D01*
G37*
G36*
G01X156500Y1214500D02*
X138500Y1232500D01*
X86000D01*
X65500Y1253000D01*
Y1326888D01*
G03Y1330112I-1500J1612D01*
G01Y1338000D01*
X66283Y1338783D01*
X66415Y1338708D01*
G03X69416Y1341709I1085J1916D01*
G01X69341Y1341841D01*
X70200Y1342700D01*
X94468D01*
G02X94703Y1341977I0J-400D01*
G03X97297I1297J-1780D01*
G02X97532Y1342700I235J323D01*
G01X97800D01*
X100000Y1340500D01*
Y1333500D01*
X99500Y1333000D01*
X95000D01*
X85000Y1323000D01*
Y1269000D01*
X94500Y1259500D01*
X239999D01*
G02X240398Y1259108I-1J-400D01*
G03X245002I2302J48D01*
G02X245401Y1259500I400J-8D01*
G01X257850D01*
X257894Y1259358D01*
G03X262106I2106J642D01*
G01X262150Y1259500D01*
X277850D01*
X277894Y1259358D01*
G03X282106I2106J642D01*
G01X282150Y1259500D01*
X295500D01*
X298000Y1257000D01*
Y1240921D01*
G03X297983Y1239116I2000J-921D01*
G01X298000Y1239078D01*
Y1238500D01*
X292000Y1232500D01*
X180000D01*
X162000Y1214500D01*
X156500D01*
G37*
G36*
G01X145784Y1346716D02*
X136600Y1355900D01*
Y1382400D01*
X104400Y1414600D01*
X101100D01*
X95400Y1420300D01*
Y1430000D01*
X98100Y1432700D01*
X110200D01*
X165700Y1377200D01*
X179000D01*
X184000Y1382200D01*
Y1421000D01*
X172255Y1432745D01*
G02X172393Y1433401I283J283D01*
G03X169543Y1436251I-798J2052D01*
G02X168887Y1436113I-373J145D01*
G01X154500Y1450500D01*
X103500D01*
X91500Y1438500D01*
X85383D01*
X75500Y1448383D01*
Y1472500D01*
X79258Y1476258D01*
X220242D01*
X241500Y1455000D01*
X321000D01*
X333000Y1443000D01*
Y1367500D01*
X322500Y1357000D01*
X228536D01*
G02X228300Y1357723I0J400D01*
G03X225700I-1300J1777D01*
G02X225464Y1357000I-236J-323D01*
G01X180000D01*
X177751Y1354751D01*
X177744Y1354745D01*
G03X177450Y1354451I1403J-1697D01*
G01X177444Y1354444D01*
X169716Y1346716D01*
X145784D01*
G37*
G36*
G01X148780Y3004D02*
Y8000D01*
X1029402D01*
Y728530D01*
X1034398D01*
Y3937D01*
G02X1033465Y3004I-933J0D01*
G01X148780D01*
G37*
G36*
G01X850000Y52000D02*
X842195Y59805D01*
X842199Y59893D01*
G03X837894Y60642I-2199J106D01*
G01X837850Y60500D01*
X822150D01*
X822106Y60642D01*
G03X817894I-2106J-642D01*
G01X817850Y60500D01*
X802150D01*
X802106Y60642D01*
G03X797894I-2106J-642D01*
G01X797850Y60500D01*
X782150D01*
X782106Y60642D01*
G03X777894I-2106J-642D01*
G01X777850Y60500D01*
X762150D01*
X762106Y60642D01*
G03X757894I-2106J-642D01*
G01X757850Y60500D01*
X742150D01*
X742106Y60642D01*
G03X737894I-2106J-642D01*
G01X737850Y60500D01*
X722150D01*
X722106Y60642D01*
G03X717894I-2106J-642D01*
G01X717850Y60500D01*
X702150D01*
X702106Y60642D01*
G03X697894I-2106J-642D01*
G01X697850Y60500D01*
X682150D01*
X682106Y60642D01*
G03X677894I-2106J-642D01*
G01X677850Y60500D01*
X662150D01*
X662106Y60642D01*
G03X657894I-2106J-642D01*
G01X657850Y60500D01*
X642150D01*
X642106Y60642D01*
G03X637894I-2106J-642D01*
G01X637850Y60500D01*
X622150D01*
X622106Y60642D01*
G03X617894I-2106J-642D01*
G01X617850Y60500D01*
X602150D01*
X602106Y60642D01*
G03X597894I-2106J-642D01*
G01X597850Y60500D01*
X582150D01*
X582106Y60642D01*
G03X577894I-2106J-642D01*
G01X577850Y60500D01*
X562150D01*
X562106Y60642D01*
G03X557894I-2106J-642D01*
G01X557850Y60500D01*
X542150D01*
X542106Y60642D01*
G03X537894I-2106J-642D01*
G01X537850Y60500D01*
X522150D01*
X522106Y60642D01*
G03X517894I-2106J-642D01*
G01X517850Y60500D01*
X502150D01*
X502106Y60642D01*
G03X497894I-2106J-642D01*
G01X497850Y60500D01*
X482150D01*
X482106Y60642D01*
G03X477894I-2106J-642D01*
G01X477850Y60500D01*
X462150D01*
X462106Y60642D01*
G03X457894I-2106J-642D01*
G01X457850Y60500D01*
X442150D01*
X442106Y60642D01*
G03X437894I-2106J-642D01*
G01X437850Y60500D01*
X422150D01*
X422106Y60642D01*
G03X417894I-2106J-642D01*
G01X417850Y60500D01*
X402150D01*
X402106Y60642D01*
G03X397894I-2106J-642D01*
G01X397850Y60500D01*
X342150D01*
X342106Y60642D01*
G03X337894I-2106J-642D01*
G01X337850Y60500D01*
X322150D01*
X322106Y60642D01*
G03X317894I-2106J-642D01*
G01X317850Y60500D01*
X302150D01*
X302106Y60642D01*
G03X297894I-2106J-642D01*
G01X297850Y60500D01*
X207500D01*
X149214Y118786D01*
Y159803D01*
X149223Y159833D01*
G03Y161167I-2098J667D01*
G01X149214Y161197D01*
Y189214D01*
X160500Y200500D01*
X175500D01*
X183000Y208000D01*
Y236000D01*
X181000Y238000D01*
X177000D01*
X171000Y244000D01*
X163000D01*
X158500Y239500D01*
X144500D01*
X143500Y240500D01*
Y247700D01*
X151800Y256000D01*
X242000D01*
X261500Y236500D01*
X296000D01*
X367500Y308000D01*
X396500D01*
X409500Y295000D01*
Y212500D01*
X419306Y202694D01*
G02X419173Y202041I-283J-282D01*
G03X422041Y199173I827J-2041D01*
G02X422694Y199306I371J-150D01*
G01X430000Y192000D01*
X790829D01*
G03X793857I1514J1599D01*
G01X845500D01*
X866500Y171000D01*
X926000D01*
X938000Y159000D01*
Y140921D01*
G03Y139079I2000J-921D01*
G01Y126000D01*
X864000Y52000D01*
X850000D01*
G37*
G36*
G01X170000Y476500D02*
X168500Y478000D01*
Y529019D01*
X156568Y540951D01*
Y542268D01*
G02X157088Y542650I400J0D01*
G03Y546850I662J2100D01*
G02X156568Y547232I-120J382D01*
G01Y548653D01*
G02X157050Y549045I400J0D01*
G03Y553355I450J2155D01*
G02X156568Y553747I-82J392D01*
G01Y557232D01*
X150900Y562900D01*
Y572141D01*
X151079Y572160D01*
G03Y576540I-229J2190D01*
G01X150900Y576559D01*
Y600900D01*
X159500Y609500D01*
Y635000D01*
X155000Y639500D01*
X146000D01*
X143000Y642500D01*
Y652500D01*
X147000Y656500D01*
X170559D01*
G02X170934Y655962I0J-400D01*
G03X175066I2066J-762D01*
G02X175441Y656500I375J138D01*
G01X194500D01*
X232500Y618500D01*
X258388D01*
G03X261612I1612J1500D01*
G01X278388D01*
G03X281612I1612J1500D01*
G01X319000D01*
X330938Y606562D01*
X330819Y606422D01*
G03X333922Y603319I1681J-1422D01*
G01X334062Y603438D01*
X337821Y599679D01*
X337831Y599617D01*
G03X338000Y599079I2168J386D01*
G01Y578082D01*
G03X337942Y574914I1500J-1612D01*
G01X338000Y574856D01*
Y574281D01*
X337942Y574223D01*
G03X338000Y571055I1558J-1556D01*
G01Y565000D01*
X249500Y476500D01*
X170000D01*
G37*
G36*
G01X208690Y893500D02*
X202203Y899987D01*
X202201Y900066D01*
G03X200066Y902201I-2201J-66D01*
G01X199987Y902203D01*
X181000Y921190D01*
Y946468D01*
G02X181492Y946857I400J0D01*
G03Y951143I508J2143D01*
G02X181000Y951532I-92J389D01*
G01Y956500D01*
X176418Y961082D01*
G03X175605Y961905I-1918J-1082D01*
G01X175582Y961918D01*
X160000Y977500D01*
Y993500D01*
X183000Y1016500D01*
Y1047000D01*
X181000Y1049000D01*
X177000D01*
X171000Y1055000D01*
X163000D01*
X157000Y1049000D01*
X150500D01*
X144000Y1055500D01*
Y1067200D01*
X145400Y1068600D01*
X145847D01*
G02X146192Y1067999I0J-400D01*
G03X149998I1903J-1109D01*
G02X150343Y1068600I345J201D01*
G01X193000D01*
X219034Y1042566D01*
G02X218943Y1041932I-283J-283D01*
G03X221932Y1038943I1057J-1932D01*
G02X222566Y1039034I351J-192D01*
G01X239034Y1022566D01*
G02X238943Y1021932I-283J-283D01*
G03X241932Y1018943I1057J-1932D01*
G02X242566Y1019034I351J-192D01*
G01X279034Y982566D01*
G02X278943Y981932I-283J-283D01*
G03X281932Y978943I1057J-1932D01*
G02X282566Y979034I351J-192D01*
G01X313500Y948100D01*
Y895000D01*
X312000Y893500D01*
X208690D01*
G37*
G36*
G01X188000Y1760000D02*
X185500Y1762500D01*
Y1766236D01*
X176571Y1775165D01*
Y1788951D01*
X179682Y1792062D01*
X204938D01*
X214500Y1782500D01*
Y1768500D01*
X206000Y1760000D01*
X205493D01*
X205462Y1760163D01*
G03X201136I-2163J-413D01*
G01X201105Y1760000D01*
X188000D01*
G37*
G36*
G01X516853Y1557000D02*
X483649Y1590204D01*
X339796D01*
X263500Y1666500D01*
Y1722500D01*
X295000Y1754000D01*
X324500D01*
X330500Y1760000D01*
X378500D01*
X385500Y1753000D01*
Y1735500D01*
X383500Y1733500D01*
X377500D01*
X371500Y1739500D01*
X322500D01*
X312317Y1729317D01*
G03X311197Y1728215I883J-2017D01*
G01X311182Y1728182D01*
X302000Y1719000D01*
Y1667000D01*
X322000Y1647000D01*
X347329D01*
G03X349171I921J2000D01*
G01X655000D01*
X685500Y1677500D01*
X810500D01*
X835500Y1652500D01*
Y1603000D01*
X789500Y1557000D01*
X516853D01*
G37*
G36*
G01X365000Y407650D02*
Y408850D01*
X365142Y408894D01*
G03Y413106I-642J2106D01*
G01X365000Y413150D01*
Y427054D01*
X365163Y427085D01*
G03X366957Y429364I-405J2164D01*
G01X366952Y429452D01*
X368500Y431000D01*
X392000D01*
X406000Y417000D01*
Y385500D01*
X390000Y369500D01*
X367500D01*
X366967Y370033D01*
G03X365192Y373400I-1867J1167D01*
G02X365000Y373600I8J200D01*
G01Y386798D01*
G03Y391202I0J2202D01*
G01Y392298D01*
G03Y396702I0J2202D01*
G01Y397850D01*
X365142Y397894D01*
G03Y402106I-642J2106D01*
G01X365000Y402150D01*
Y403350D01*
X365142Y403394D01*
G03Y407606I-642J2106D01*
G01X365000Y407650D01*
G37*
G36*
G01X400000Y843079D02*
Y837612D01*
G03Y834388I1500J-1612D01*
G01Y831746D01*
G03Y828254I1500J-1746D01*
G01Y803500D01*
X396000Y799500D01*
X367500D01*
X365000Y802000D01*
Y816798D01*
G03Y821202I0J2202D01*
G01Y822298D01*
G03Y826702I0J2202D01*
G01Y827850D01*
X365142Y827894D01*
G03Y832106I-642J2106D01*
G01X365000Y832150D01*
Y833350D01*
X365142Y833394D01*
G03Y837606I-642J2106D01*
G01X365000Y837650D01*
Y838850D01*
X365142Y838894D01*
G03Y843106I-642J2106D01*
G01X365000Y843150D01*
Y857500D01*
X368500Y861000D01*
X390000D01*
X400000Y851000D01*
Y844921D01*
G03Y843079I2000J-921D01*
G37*
G36*
G01X365000Y1176992D02*
Y1188298D01*
G03Y1192702I0J2202D01*
G01Y1193798D01*
G03Y1198202I0J2202D01*
G01Y1199350D01*
X365142Y1199394D01*
G03Y1203606I-642J2106D01*
G01X365000Y1203650D01*
Y1204850D01*
X365142Y1204894D01*
G03Y1209106I-642J2106D01*
G01X365000Y1209150D01*
Y1210350D01*
X365142Y1210394D01*
G03Y1214606I-642J2106D01*
G01X365000Y1214650D01*
Y1222000D01*
X375000Y1232000D01*
X396000D01*
X397000Y1233000D01*
Y1239500D01*
X398000Y1240500D01*
X401000D01*
X403500Y1238000D01*
Y1230000D01*
X399500Y1226000D01*
Y1195000D01*
X403500Y1191000D01*
Y1179000D01*
X395500Y1171000D01*
X367500D01*
X365789Y1172711D01*
G02X365799Y1173287I282J283D01*
G03X365125Y1176942I-1499J1613D01*
G01X365000Y1176992D01*
G37*
G36*
G01X384000Y1731000D02*
X390883Y1724117D01*
X390857Y1724008D01*
G03X393085Y1721300I2143J-508D01*
G02X393500Y1720900I15J-400D01*
G01Y1691421D01*
G03Y1689579I2000J-921D01*
G01Y1673000D01*
X390000Y1669500D01*
X367500D01*
X365000Y1672000D01*
Y1686798D01*
G03Y1691202I0J2202D01*
G01Y1692298D01*
G03Y1696702I0J2202D01*
G01Y1697850D01*
X365142Y1697894D01*
G03Y1702106I-642J2106D01*
G01X365000Y1702150D01*
Y1703350D01*
X365142Y1703394D01*
G03Y1707606I-642J2106D01*
G01X365000Y1707650D01*
Y1708850D01*
X365142Y1708894D01*
G03Y1713106I-642J2106D01*
G01X365000Y1713150D01*
Y1725115D01*
G02X365446Y1725513I400J1D01*
G03X367285Y1729229I254J2187D01*
G02X367290Y1729790I287J278D01*
G01X368500Y1731000D01*
X384000D01*
G37*
G36*
G01X1011098Y1509646D02*
Y1426599D01*
X1007599Y1423100D01*
X998900D01*
X998300Y1422500D01*
X934500D01*
X932000Y1425000D01*
Y1509500D01*
X932700Y1510200D01*
X1010544D01*
X1011098Y1509646D01*
G37*
G36*
G01X1010498Y1514400D02*
X931437D01*
X930262Y1515575D01*
Y1604517D01*
X932234Y1606489D01*
X980451D01*
X988690Y1598250D01*
X1010129D01*
X1011156Y1597223D01*
Y1515058D01*
X1010498Y1514400D01*
G37*
%LPC*%
G75*
G36*
G01X73330Y1275657D02*
G03X73099Y1275166I150J-371D01*
G02X70170Y1276540I-2099J-666D01*
G03X70401Y1277031I-150J371D01*
G02X73330Y1275657I2099J666D01*
G37*
G36*
G01X114230Y1252819D02*
G03Y1252281I296J-269D01*
G02X110970I-1630J-1481D01*
G03Y1252819I-296J269D01*
G02X114230I1630J1481D01*
G37*
G36*
G01X170842Y1460380D02*
Y1452929D01*
X170840Y1452928D01*
X162938D01*
Y1460380D01*
X170842D01*
G37*
G36*
G01X149665Y1470858D02*
G03Y1470296I285J-281D01*
G02X146525I-1570J-1544D01*
G03Y1470858I-285J281D01*
G02X149665I1570J1544D01*
G37*
G36*
G01X296024Y1449997D02*
G03X295439I-292J-273D01*
G02Y1453003I-1609J1503D01*
G03X296024I292J273D01*
G02Y1449997I1609J-1503D01*
G37*
G36*
G01X284224Y1449897D02*
G03X283639I-292J-273D01*
G02Y1452903I-1609J1503D01*
G03X284224I293J273D01*
G02Y1449897I1609J-1503D01*
G37*
G36*
G01X308024Y1449797D02*
G03X307439I-292J-273D01*
G02Y1452803I-1609J1503D01*
G03X308024I293J273D01*
G02Y1449797I1609J-1503D01*
G37*
G36*
G01X331503Y1433561D02*
G03Y1432976I273J-293D01*
G02X328497I-1503J-1609D01*
G03Y1433561I-273J292D01*
G02X331503I1503J1609D01*
G37*
G36*
G01X271603Y1427891D02*
G03Y1427306I273J-292D01*
G02X268597I-1503J-1609D01*
G03Y1427891I-273J293D01*
G02X271603I1503J1609D01*
G37*
G36*
G01X331503Y1421861D02*
G03Y1421276I273J-293D01*
G02X328497I-1503J-1609D01*
G03Y1421861I-273J292D01*
G02X331503I1503J1609D01*
G37*
G36*
G01X299908Y1419300D02*
G03X299700Y1419092I-8J-200D01*
G02X297415Y1421200I-2200J-92D01*
G03X297800Y1421585I-15J400D01*
G01Y1421592D01*
G03X297592Y1421800I-200J8D01*
G02X299700Y1424085I-92J2200D01*
G03X300085Y1423700I400J15D01*
G01X300092D01*
G03X300300Y1423908I8J200D01*
G02X302585Y1421800I2200J92D01*
G03X302200Y1421415I15J-400D01*
G01Y1421408D01*
G03X302408Y1421200I200J-8D01*
G02X300300Y1418915I92J-2200D01*
G03X299915Y1419300I-400J-15D01*
G01X299908D01*
G37*
G36*
G01X271503Y1415724D02*
G03Y1415139I273J-292D01*
G02X268497I-1503J-1609D01*
G03Y1415724I-273J293D01*
G02X271503I1503J1609D01*
G37*
G36*
G01X331803Y1409491D02*
G03Y1408906I273J-292D01*
G02X328797I-1503J-1609D01*
G03Y1409491I-273J293D01*
G02X331803I1503J1609D01*
G37*
G36*
G01X289361Y1378497D02*
G03X288776I-293J-273D01*
G02Y1381503I-1609J1503D01*
G03X289361I292J273D01*
G02Y1378497I1609J-1503D01*
G37*
G36*
G01X191534Y1452626D02*
G02X189355Y1452676I-1133J-1888D01*
G03X189387Y1453362I-189J353D01*
G02X188488Y1455037I1113J1676D01*
G01Y1458237D01*
G02X189387Y1459912I2012J-1D01*
G03X189355Y1460598I-221J333D01*
G02X191534Y1460648I1046J1938D01*
G03Y1459962I206J-343D01*
G02X192512Y1458247I-1034J-1726D01*
G01Y1454950D01*
X192504Y1454863D01*
G02X191534Y1453312I-2004J174D01*
G03Y1452626I206J-343D01*
G37*
G36*
G01X178107Y1446137D02*
G02X175547Y1449623I-1615J1497D01*
G03X175612Y1450307I-171J361D01*
G02X176800Y1453942I1188J1623D01*
G01X180000D01*
G02X182012Y1451940I0J-2012D01*
G01Y1451843D01*
X182004Y1451756D01*
G02X181188Y1450307I-2004J174D01*
G03X181253Y1449623I236J-323D01*
G02X178693Y1446137I-945J-1989D01*
G03X178107I-293J-272D01*
G37*
G36*
G01X375807Y96591D02*
G03X375193I-307J-255D01*
G02Y99409I-1693J1409D01*
G03X375807I307J255D01*
G02Y96591I1693J-1409D01*
G37*
G36*
G01X376532Y79954D02*
G03X375947Y79939I-286J-280D01*
G02X375868Y82946I-1647J1461D01*
G03X376453Y82961I286J280D01*
G02X379835Y82856I1647J-1461D01*
G03X380465I315J246D01*
G02Y80144I1735J-1356D01*
G03X379835I-315J-246D01*
G02X376532Y79954I-1735J1356D01*
G37*
G36*
G01X193156Y238646D02*
G02X192318Y236607I1344J-1744D01*
G03X191686Y236876I-396J-54D01*
G02X188488Y238501I-1186J1625D01*
G01Y241701D01*
G02X191686Y243326I2012J0D01*
G03X192318Y243595I236J323D01*
G02X193156Y241556I2182J-295D01*
G03X192512Y241239I-244J-317D01*
G01Y238963D01*
G03X193156Y238646I400J0D01*
G37*
G36*
G01X173410Y175602D02*
X169110D01*
G02Y184004I0J4201D01*
G01X173410D01*
G02X177378Y181185I0J-4202D01*
G03X178101Y181114I378J131D01*
G02X178170Y178775I1899J-1114D01*
G03X177453Y178661I-332J-223D01*
G02X173410Y175602I-4043J1142D01*
G37*
G36*
G01X170842Y649356D02*
Y641905D01*
X170840Y641904D01*
X162938D01*
Y649356D01*
X170842D01*
G37*
G36*
G01X288324Y614197D02*
G03X287739I-292J-273D01*
G02Y617203I-1609J1503D01*
G03X288324I292J273D01*
G02Y614197I1609J-1503D01*
G37*
G36*
G01X312224Y613997D02*
G03X311639I-292J-273D01*
G02Y617003I-1609J1503D01*
G03X312224I293J273D01*
G02Y613997I1609J-1503D01*
G37*
G36*
G01X271303Y593124D02*
G03Y592539I273J-293D01*
G02X268297I-1503J-1609D01*
G03Y593124I-273J292D01*
G02X271303I1503J1609D01*
G37*
G36*
G01X299908Y583300D02*
G03X299700Y583092I-8J-200D01*
G02X297415Y585200I-2200J-92D01*
G03X297800Y585585I-15J400D01*
G01Y585592D01*
G03X297592Y585800I-200J8D01*
G02X299700Y588085I-92J2200D01*
G03X300085Y587700I400J15D01*
G01X300092D01*
G03X300300Y587908I8J200D01*
G02X302585Y585800I2200J92D01*
G03X302200Y585415I15J-400D01*
G01Y585408D01*
G03X302408Y585200I200J-8D01*
G02X300300Y582915I92J-2200D01*
G03X299915Y583300I-400J-15D01*
G01X299908D01*
G37*
G36*
G01X271503Y581224D02*
G03Y580639I273J-293D01*
G02X268497I-1503J-1609D01*
G03Y581224I-273J292D01*
G02X271503I1503J1609D01*
G37*
G36*
G01Y569324D02*
G03Y568739I273J-293D01*
G02X268497I-1503J-1609D01*
G03Y569324I-273J292D01*
G02X271503I1503J1609D01*
G37*
G36*
G01X294861Y553997D02*
G03X294276I-293J-273D01*
G02Y557003I-1609J1503D01*
G03X294861I292J273D01*
G02Y553997I1609J-1503D01*
G37*
G36*
G01X190357Y529293D02*
G03Y528708I273J-293D01*
G02X187351I-1503J-1609D01*
G03Y529293I-273J292D01*
G02X190357I1503J1609D01*
G37*
G36*
G01X191590Y641626D02*
G02X189410I-1090J-1913D01*
G03X189426Y642312I-198J348D01*
G02X188488Y644013I1073J1701D01*
G01Y647213D01*
G02X189426Y648914I2011J0D01*
G03X189410Y649600I-214J338D01*
G02X191590I1090J1913D01*
G03X191574Y648914I198J-348D01*
G02X192512Y647223I-1074J-1701D01*
G01Y643926D01*
X192504Y643839D01*
G02X191574Y642312I-2004J174D01*
G03X191590Y641626I214J-338D01*
G37*
G36*
G01X178107Y635120D02*
G02X175542Y638604I-1615J1497D01*
G03X175607Y639287I-172J361D01*
G02X176800Y642918I1193J1620D01*
G01X180000D01*
G02X182012Y640916I0J-2012D01*
G01Y640819D01*
X182004Y640732D01*
G02X181193Y639287I-2004J175D01*
G03X181258Y638604I237J-322D01*
G02X178693Y635120I-950J-1987D01*
G03X178107I-293J-272D01*
G37*
G36*
G01X200297Y967798D02*
G03Y967179I253J-310D01*
G02X197503I-1397J-1702D01*
G03Y967798I-253J309D01*
G02X200297I1397J1702D01*
G37*
G36*
G01X191645Y1047164D02*
G02X189466Y1047114I-1046J-1938D01*
G03Y1047800I-206J343D01*
G02X188488Y1049525I1034J1726D01*
G01Y1052725D01*
G02X189466Y1054450I2012J-1D01*
G03Y1055136I-206J343D01*
G02X191645Y1055086I1133J1888D01*
G03X191613Y1054400I189J-353D01*
G02X192512Y1052735I-1112J-1676D01*
G01Y1049438D01*
X192504Y1049351D01*
G02X191613Y1047850I-2004J175D01*
G03X191645Y1047164I221J-333D01*
G37*
G36*
G01X375199Y1753931D02*
G03X374614I-292J-273D01*
G02Y1756937I-1609J1503D01*
G03X375199I293J273D01*
G02Y1753931I1609J-1503D01*
G37*
G36*
G01X274793Y1724643D02*
G03X274208I-292J-273D01*
G02Y1727649I-1609J1503D01*
G03X274793I293J273D01*
G02Y1724643I1609J-1503D01*
G37*
G36*
G01X293723Y1687310D02*
G02X291359Y1690935I-1523J1590D01*
G03X291404Y1691652I-153J370D01*
G02X290404Y1693647I996J1747D01*
G03X289898Y1694081I-397J49D01*
G02X287134Y1695803I-598J2119D01*
G03X286452Y1696008I-393J-72D01*
G02X282988Y1697400I-1452J1392D01*
G01Y1700600D01*
G02X286452Y1701992I2012J0D01*
G03X287134Y1702197I289J277D01*
G02X287385Y1700712I2166J-398D01*
G03X287011Y1700612I-174J-99D01*
G02X287012Y1700610I-1799J-901D01*
G01Y1697990D01*
G03X287702Y1697715I400J0D01*
G02X291469Y1695820I1598J-1515D01*
G03X291952Y1695361I394J-69D01*
G02X292400Y1695412I450J-1961D01*
G01X295600D01*
G02X297612Y1693410I0J-2012D01*
G01Y1693313D01*
X297604Y1693226D01*
G02X296596Y1691652I-2004J174D01*
G03X296641Y1690935I198J-347D01*
G02X294277Y1687310I-841J-2035D01*
G03X293723I-277J-289D01*
G37*
G54D19*
X171260Y585315D03*
Y990827D03*
G54D18*
X98300Y1255900D03*
X72500Y1302697D03*
X118250Y1252050D03*
X72500Y1307697D03*
X71000Y1335488D03*
X157325Y1223850D03*
X80300Y1451000D03*
X82748Y1465560D03*
X130000Y1470000D03*
X122000D03*
X114000D03*
X160000Y1360000D03*
X151125Y1376608D03*
X193400Y1373000D03*
X167301Y1366838D03*
X158875Y1376100D03*
X180000Y1440000D03*
X200000D03*
X171895Y1450453D03*
X200000Y1460000D03*
X148095Y1453504D03*
Y1462953D03*
X140000Y1464000D03*
X173100Y1466300D03*
X215000Y1368000D03*
X240000Y1367500D03*
X260000Y1400000D03*
Y1420000D03*
Y1440000D03*
X240000D03*
Y1420000D03*
Y1400000D03*
X273500Y1407500D03*
X311500Y1389000D03*
X280000Y1380000D03*
X300984Y1433500D03*
X303500Y1389000D03*
X297600Y1392000D03*
X319500Y1389000D03*
X179147Y137913D03*
X200000Y80000D03*
X158300Y135200D03*
X200000Y200000D03*
Y180000D03*
X198800Y158000D03*
X167298Y151203D03*
X154875Y160500D03*
X148095Y246417D03*
X172900Y249400D03*
X240000Y140000D03*
X220000D03*
X260000Y100000D03*
Y80000D03*
X220000D03*
X240000D03*
X260000Y160000D03*
X220000D03*
X240000D03*
X220000Y200000D03*
Y180000D03*
X240000D03*
Y200000D03*
X260000D03*
Y180000D03*
Y220000D03*
X240000D03*
X220000D03*
X340000Y80000D03*
Y100000D03*
X320000Y80000D03*
X300000Y140000D03*
X320000D03*
X340000D03*
Y120000D03*
X320000D03*
X300000D03*
X280000D03*
Y100000D03*
X300000D03*
X320000D03*
X300000Y80000D03*
X280000D03*
X340000Y180000D03*
Y160000D03*
X320000D03*
X280000Y180000D03*
Y200000D03*
X300000D03*
X292600Y166955D03*
X280000Y220000D03*
X300000D03*
X320000D03*
Y240000D03*
X340000D03*
Y260000D03*
X363750Y65250D03*
X400000Y100000D03*
Y80000D03*
X420000Y100000D03*
Y80000D03*
Y120000D03*
Y140000D03*
X400000Y120000D03*
Y140000D03*
X380000D03*
X360000D03*
X357250Y124000D03*
X352500Y68500D03*
X358500Y93500D03*
X363750Y73300D03*
X360000Y180000D03*
X400000Y200000D03*
X380000D03*
Y180000D03*
X400000D03*
X420000D03*
Y160000D03*
X400000D03*
X380000D03*
X360000D03*
X400000Y220000D03*
X360000Y260000D03*
Y280000D03*
X460000Y100000D03*
X480000D03*
X440000D03*
X480000Y120000D03*
Y140000D03*
Y80000D03*
X460000D03*
X440000D03*
X460000Y120000D03*
Y140000D03*
X440000D03*
Y120000D03*
X480000Y160000D03*
Y180000D03*
X440000D03*
X460000D03*
Y160000D03*
X440000D03*
X560000Y100000D03*
X540000D03*
X520000D03*
X500000D03*
Y140000D03*
Y120000D03*
X520000D03*
Y140000D03*
X500000Y80000D03*
X520000D03*
X540000Y140000D03*
Y120000D03*
X560000D03*
Y140000D03*
X540000Y80000D03*
X560000D03*
X500000Y160000D03*
X520000D03*
Y180000D03*
X500000D03*
X540000Y160000D03*
X560000D03*
Y180000D03*
X540000D03*
X640000Y100000D03*
X620000D03*
X600000D03*
X580000D03*
Y120000D03*
Y140000D03*
X600000Y120000D03*
Y140000D03*
X580000Y80000D03*
X600000D03*
X620000Y140000D03*
Y120000D03*
X640000D03*
Y140000D03*
X620000Y80000D03*
X640000D03*
X580000Y160000D03*
X600000D03*
Y180000D03*
X580000D03*
X620000Y160000D03*
X640000D03*
Y180000D03*
X620000D03*
X700000Y120000D03*
X680000Y100000D03*
X660000D03*
Y140000D03*
Y120000D03*
Y80000D03*
X680000Y120000D03*
Y140000D03*
X700000D03*
X680000Y80000D03*
X700000D03*
Y100000D03*
Y180000D03*
Y160000D03*
X660000D03*
Y180000D03*
X680000Y160000D03*
Y180000D03*
X720000Y140000D03*
Y120000D03*
X740000D03*
Y140000D03*
X720000Y100000D03*
X740000Y80000D03*
X720000D03*
X740000Y100000D03*
X760000Y120000D03*
X780000D03*
X760000Y140000D03*
X780000D03*
X760000Y100000D03*
Y80000D03*
X780000D03*
Y100000D03*
X740000Y180000D03*
X720000D03*
Y160000D03*
X780000D03*
X760000D03*
X740000D03*
X760000Y180000D03*
X780000D03*
X860000Y60000D03*
Y140000D03*
X840000D03*
X820000D03*
X800000D03*
Y120000D03*
X820000D03*
X840000D03*
X860000D03*
X800000Y100000D03*
X820000D03*
X840000D03*
X860000D03*
X800000Y80000D03*
X820000D03*
X840000D03*
X860000D03*
X816000Y187000D03*
X828500Y171000D03*
X840000Y174250D03*
X820500Y171000D03*
X880000Y120000D03*
Y100000D03*
Y80000D03*
X908493Y136513D03*
X920000Y120000D03*
X900000D03*
Y100000D03*
X885993Y134893D03*
X869250Y144750D03*
X926347Y155500D03*
X896547Y150803D03*
X890469Y164804D03*
X864975Y148875D03*
X180000Y480000D03*
X200000D03*
X158500Y569500D03*
X180000Y520000D03*
X200000D03*
X165138Y536500D03*
X174000Y553500D03*
X195500Y531250D03*
Y546250D03*
Y538750D03*
X195250Y561300D03*
X180000Y620000D03*
X200000Y580000D03*
X180000D03*
Y600000D03*
X171595Y609429D03*
Y624429D03*
X171895Y639429D03*
X148095Y642480D03*
Y651929D03*
X220000Y480000D03*
X260000Y560000D03*
X220000Y520000D03*
X260000D03*
Y600000D03*
X220000Y620000D03*
X240000Y600000D03*
Y580000D03*
X313000Y559000D03*
X332500Y597000D03*
Y589000D03*
X288000Y586484D03*
X329600Y583200D03*
X180000Y1000000D03*
X194200Y985900D03*
X180000Y980000D03*
X201125Y957200D03*
X195500Y949750D03*
X148095Y1057441D03*
X173000Y1060400D03*
X220000Y940000D03*
X240000D03*
X260000D03*
X240000Y1000000D03*
X260000Y980000D03*
X208875Y957200D03*
X220000Y1020000D03*
X280000Y940000D03*
X300000D03*
X191353Y1772940D03*
X197900Y1781500D03*
X207600Y1777500D03*
X288000Y1742500D03*
X293000D03*
X284000Y1731250D03*
X343709Y1744187D03*
X343668Y1750741D03*
X351750Y1751000D03*
X370000Y411000D03*
Y405500D03*
X375500D03*
X381000D03*
X375500Y411000D03*
X381000D03*
X370000Y400000D03*
X381000D03*
X375500D03*
X370000Y389000D03*
Y394500D03*
X375500D03*
Y389000D03*
X381000D03*
Y394500D03*
X397000Y414750D03*
X401500Y401500D03*
X397000Y383750D03*
X401500Y410250D03*
X370000Y841000D03*
Y835500D03*
X375500D03*
X381000D03*
X375500Y841000D03*
X381000D03*
X370000Y830000D03*
X381000D03*
X375500D03*
X370000Y819000D03*
Y824500D03*
X375500D03*
Y819000D03*
X381000D03*
Y824500D03*
X397000Y844750D03*
X395000Y806500D03*
X370000Y1212500D03*
Y1207000D03*
X375500D03*
X381000D03*
X375500Y1212500D03*
X381000D03*
X370000Y1201500D03*
X381000D03*
X375500D03*
X370000Y1190500D03*
Y1196000D03*
X375500D03*
Y1190500D03*
X381000D03*
Y1196000D03*
X396750Y1181250D03*
X391500Y1218500D03*
X398750Y1188250D03*
X381000Y1711000D03*
X375500D03*
X381000Y1705500D03*
X375500D03*
X381000Y1694500D03*
Y1689000D03*
X375500D03*
Y1694500D03*
X370000D03*
Y1689000D03*
Y1705500D03*
Y1711000D03*
X381000Y1700000D03*
X375500D03*
X370000D03*
X388750Y1673000D03*
X369100Y1673700D03*
X376890Y1678000D03*
X379000Y1726000D03*
G54D20*
X206700Y575000D03*
X284000Y541344D03*
Y548844D03*
X807756Y1594275D03*
X401500Y395500D03*
G54D17*
X82087Y1245394D03*
X162008Y191614D03*
Y597126D03*
G54D16*
X11811Y949378D03*
Y1067489D03*
Y1484811D03*
Y1445441D03*
%LPD*%
G75*
G54D10*
G01X-106883Y-224955D02*
Y-304955D01*
G01Y-260455D02*
X1019417D01*
G01X-106883Y-304955D02*
X1019417D01*
G01X-110883Y-208955D02*
G02I-12000J0D01*
G01X-116033D02*
G02I-6850J0D01*
G01X-122883Y-224955D02*
Y-192955D01*
G01X-106883Y-208955D02*
X-138883D01*
G01X-106883Y-224955D02*
X1019417D01*
G01X71000Y125236D02*
X77236Y119000D01*
X96000D01*
G01X71000Y530748D02*
X77748Y524000D01*
X96000D01*
G01X71000Y936260D02*
X77260Y930000D01*
X96000D01*
G01X104000Y1747800D02*
X103300Y1748500D01*
X86500D01*
X85100Y1747100D01*
X71184D01*
X71000Y1747284D01*
G01X231917Y-224955D02*
Y-304955D01*
G01X369417Y-224955D02*
Y-304955D01*
G01X484417Y-224955D02*
Y-304955D01*
G01X651917Y-224955D02*
Y-304955D01*
G01X821917Y-224955D02*
Y-304955D01*
G01X959000Y1631000D02*
Y1657000D01*
G01D02*
Y1675000D01*
G01X1019417Y-224955D02*
Y-304955D01*
G01X1047417Y-208955D02*
G02I-12000J0D01*
G01X1042267D02*
G02I-6850J0D01*
G01X1035417Y-224955D02*
Y-192955D01*
G01X1051417Y-208955D02*
X1019417D01*
X5500Y40982D03*
Y20982D03*
X10018Y5500D03*
X30018D03*
X5500Y120982D03*
Y100982D03*
Y80982D03*
Y60982D03*
Y180982D03*
Y160982D03*
Y140982D03*
Y260982D03*
Y240982D03*
Y220982D03*
Y200982D03*
Y320982D03*
Y300982D03*
Y280982D03*
Y400982D03*
Y380982D03*
Y360982D03*
Y340982D03*
Y480982D03*
Y460982D03*
Y440982D03*
Y420982D03*
Y540982D03*
Y520982D03*
Y500982D03*
X16500Y624765D03*
Y618765D03*
Y612166D03*
Y606166D03*
Y598197D03*
X20000Y607620D03*
Y610820D03*
Y620218D03*
Y623418D03*
X16500Y700355D03*
Y694355D03*
Y687757D03*
Y681757D03*
Y675158D03*
Y669158D03*
Y662226D03*
Y657000D03*
Y649500D03*
Y644530D03*
Y637363D03*
Y631363D03*
X20000Y658013D03*
Y661213D03*
Y670612D03*
Y673812D03*
Y683210D03*
Y686410D03*
Y632817D03*
Y636017D03*
Y695809D03*
Y699009D03*
Y645415D03*
Y648615D03*
X24500Y732329D03*
X16500Y769646D03*
Y763646D03*
Y757048D03*
Y725552D03*
Y719552D03*
Y712953D03*
Y706953D03*
Y751658D03*
Y732500D03*
X20000Y708407D03*
Y711607D03*
Y721006D03*
Y724206D03*
Y752502D03*
Y755702D03*
Y765100D03*
Y768300D03*
X16500Y848686D03*
Y842087D03*
Y836087D03*
Y829489D03*
Y823489D03*
Y816891D03*
Y810891D03*
Y804292D03*
Y798292D03*
Y791694D03*
Y785694D03*
Y777725D03*
X20000Y837541D03*
Y840741D03*
Y787147D03*
Y790347D03*
Y799746D03*
Y802946D03*
Y812344D03*
Y815544D03*
Y824943D03*
Y828143D03*
X16500Y917678D03*
Y911678D03*
Y905079D03*
Y899079D03*
Y879883D03*
Y873883D03*
Y867284D03*
Y861284D03*
Y854686D03*
Y889500D03*
X20000Y900533D03*
Y903733D03*
Y850139D03*
Y853339D03*
Y913132D03*
Y916332D03*
Y862738D03*
Y865938D03*
Y875336D03*
Y878536D03*
Y980000D03*
Y960000D03*
Y940000D03*
X16000Y931000D03*
X5500Y980299D03*
Y1040299D03*
Y1020299D03*
Y1000299D03*
X16500Y1140024D03*
Y1120828D03*
Y1114828D03*
Y1108229D03*
Y1102229D03*
Y1133500D03*
Y1094260D03*
X20000Y1103683D03*
Y1106883D03*
Y1116281D03*
Y1119481D03*
X16500Y1209016D03*
Y1203016D03*
Y1196418D03*
Y1190418D03*
Y1183820D03*
Y1177820D03*
Y1171221D03*
Y1165221D03*
Y1158623D03*
Y1152623D03*
Y1146024D03*
X20000Y1141478D03*
Y1144678D03*
Y1191872D03*
Y1195072D03*
Y1154076D03*
Y1157276D03*
Y1204470D03*
Y1207670D03*
Y1166675D03*
Y1169875D03*
Y1179273D03*
Y1182473D03*
X24500Y1228386D03*
X16500Y1284906D03*
Y1278308D03*
Y1272308D03*
Y1265709D03*
Y1259709D03*
Y1253111D03*
Y1247721D03*
Y1221615D03*
Y1215615D03*
Y1228500D03*
X20000Y1261163D03*
Y1264363D03*
Y1273761D03*
Y1276961D03*
Y1217069D03*
Y1220269D03*
Y1248565D03*
Y1251765D03*
X16500Y1357347D03*
Y1350749D03*
Y1344749D03*
Y1338150D03*
Y1332150D03*
Y1325552D03*
Y1319552D03*
Y1303505D03*
Y1297505D03*
Y1290906D03*
X16417Y1311583D03*
X20000Y1321006D03*
Y1324206D03*
Y1333604D03*
Y1336804D03*
Y1346202D03*
Y1349402D03*
Y1286360D03*
Y1289560D03*
Y1298958D03*
Y1302158D03*
X16500Y1413741D03*
Y1407741D03*
Y1401142D03*
Y1395142D03*
Y1388544D03*
Y1382544D03*
Y1375946D03*
Y1369946D03*
Y1363347D03*
X20000Y1371399D03*
Y1374599D03*
Y1383998D03*
Y1387198D03*
Y1396596D03*
Y1399796D03*
Y1358801D03*
Y1362001D03*
Y1409195D03*
Y1412395D03*
X16500Y1573000D03*
Y1566500D03*
Y1560500D03*
Y1554000D03*
Y1548000D03*
Y1541500D03*
Y1535000D03*
Y1529000D03*
Y1521031D03*
Y1512500D03*
X20000Y1530454D03*
Y1533654D03*
Y1543052D03*
Y1546252D03*
Y1555650D03*
Y1558850D03*
Y1568249D03*
Y1571449D03*
X16500Y1644735D03*
Y1639845D03*
Y1633000D03*
Y1626500D03*
Y1620000D03*
Y1614000D03*
Y1607500D03*
Y1601500D03*
Y1595000D03*
Y1588500D03*
Y1582500D03*
X20000Y1640690D03*
Y1643890D03*
Y1593496D03*
Y1590296D03*
Y1606094D03*
Y1602894D03*
Y1618693D03*
Y1615493D03*
Y1631291D03*
Y1628091D03*
X16500Y1669933D03*
Y1677000D03*
Y1683170D03*
Y1689500D03*
Y1696000D03*
Y1702500D03*
Y1712000D03*
Y1717462D03*
Y1665044D03*
X20000Y1716331D03*
Y1713131D03*
Y1665887D03*
Y1669087D03*
Y1678485D03*
Y1681685D03*
Y1691083D03*
Y1694283D03*
X16500Y1749000D03*
Y1756052D03*
Y1765000D03*
Y1774500D03*
Y1784000D03*
Y1790500D03*
Y1724000D03*
Y1730658D03*
Y1736500D03*
Y1743356D03*
X20000Y1728929D03*
Y1725729D03*
Y1741528D03*
Y1738328D03*
Y1754126D03*
Y1750926D03*
X5500Y1880685D03*
Y1888685D03*
X32559Y1986626D03*
X12559D03*
X5500Y1973685D03*
Y1953685D03*
X90018Y5500D03*
X110018D03*
X50018D03*
X70018D03*
X96000Y119000D03*
X99500Y95940D03*
Y91540D03*
Y77042D03*
Y72642D03*
Y58244D03*
Y53844D03*
X71000Y125236D03*
X99500Y146333D03*
Y141933D03*
X60306Y212338D03*
X80153Y230246D03*
X85427Y239715D03*
X100400Y208300D03*
X99500Y482554D03*
Y478154D03*
Y463656D03*
Y459256D03*
X71000Y530748D03*
X96000Y524000D03*
X99500Y551845D03*
Y547445D03*
Y501452D03*
Y497052D03*
X95900Y605500D03*
X62426Y607740D03*
X80153Y635758D03*
X85223Y645227D03*
X99500Y906964D03*
Y902564D03*
Y888066D03*
Y883666D03*
Y869168D03*
Y864768D03*
X96000Y930000D03*
X71000Y936260D03*
X99500Y957357D03*
Y952957D03*
X81689Y1039600D03*
X77750Y1056750D03*
X96500Y1011200D03*
X64037Y1016654D03*
X99500Y1274680D03*
Y1270280D03*
X71000Y1341772D03*
X96000Y1335000D03*
X99500Y1312476D03*
Y1308076D03*
Y1293578D03*
Y1289178D03*
X100000Y1423000D03*
X99900Y1419600D03*
X99500Y1362869D03*
Y1358469D03*
X110000Y1470000D03*
X99300Y1431200D03*
X82748Y1455148D03*
X76750Y1462762D03*
X80153Y1446781D03*
X99500Y1713588D03*
Y1717988D03*
Y1694690D03*
Y1699090D03*
Y1675792D03*
Y1680192D03*
X71000Y1747284D03*
X104000Y1747800D03*
X99500Y1763981D03*
Y1768381D03*
X80600Y1848900D03*
X112366Y1883985D03*
X112559Y1986626D03*
X92559D03*
X72559D03*
X52559D03*
X155018Y5500D03*
X170018D03*
X184461Y103368D03*
X150557Y142854D03*
X167298Y147703D03*
X159500Y181000D03*
X173095Y244842D03*
X148000Y241500D03*
X144595Y223745D03*
Y228145D03*
X129000Y255500D03*
X144595Y274138D03*
Y278538D03*
Y293036D03*
Y297436D03*
Y311934D03*
Y316334D03*
X170500Y478500D03*
X157750Y541250D03*
X184500Y553500D03*
X159600Y581400D03*
X155500Y574000D03*
X144595Y629257D03*
X148000Y648000D03*
X173095Y650354D03*
X144595Y633657D03*
Y679650D03*
Y684050D03*
Y698548D03*
Y702948D03*
Y717446D03*
Y721846D03*
X156800Y816000D03*
X126800Y842500D03*
X178000Y960000D03*
X162200Y988000D03*
X161095Y980622D03*
X173095Y1055866D03*
X148000Y1053500D03*
X144595Y1034769D03*
Y1039169D03*
X139300Y1067000D03*
X144595Y1085162D03*
Y1089562D03*
Y1104060D03*
Y1108460D03*
Y1122958D03*
Y1127358D03*
X158052Y1216052D03*
X129150Y1252050D03*
X147956Y1347802D03*
X140125Y1381300D03*
X167301Y1363238D03*
X118000Y1470000D03*
X148000Y1458000D03*
X126000Y1466000D03*
X173095Y1461378D03*
X144595Y1440281D03*
Y1444681D03*
Y1490674D03*
Y1495074D03*
Y1509572D03*
Y1513972D03*
Y1528470D03*
Y1532870D03*
X177717Y1778162D03*
X180075Y1790692D03*
X173095Y1866890D03*
X148000Y1864000D03*
X144595Y1850193D03*
Y1845793D03*
Y1900586D03*
Y1896186D03*
Y1919484D03*
Y1915084D03*
Y1938382D03*
Y1933982D03*
X172559Y1986626D03*
X152559D03*
X132559D03*
X230018Y5500D03*
X250018D03*
X190018D03*
X210018D03*
X220500Y67500D03*
X198800Y162500D03*
Y167000D03*
X206500Y538750D03*
Y546250D03*
Y531250D03*
X195250Y576700D03*
X200250Y572100D03*
X190330Y913530D03*
X207350Y968627D03*
X198900Y974000D03*
Y978500D03*
X229500Y946600D03*
X196000Y1070300D03*
X193400Y1377500D03*
Y1382000D03*
X214500Y1459000D03*
X203299Y1763350D03*
X197900Y1786000D03*
Y1790500D03*
X252559Y1986626D03*
X232559D03*
X212559D03*
X192559D03*
X310018Y5500D03*
X330018D03*
X270018D03*
X290018D03*
X297300Y505017D03*
X273500Y597000D03*
Y589000D03*
Y585000D03*
Y577000D03*
X284000Y612000D03*
X273500Y573000D03*
Y565000D03*
X296000Y612000D03*
X292000D03*
X316000D03*
X308000D03*
X304000D03*
X290580Y559000D03*
X298450D03*
X320100Y587200D03*
X317500Y559000D03*
X295200Y903000D03*
X305200D03*
Y913000D03*
X295200D03*
X292500Y965500D03*
X295000Y1245000D03*
X294500Y1254000D03*
X301400Y1401500D03*
X315500Y1389000D03*
X293100Y1383500D03*
X284900D03*
X273500Y1419500D03*
Y1411500D03*
Y1423500D03*
X326500Y1417500D03*
Y1425700D03*
Y1405400D03*
Y1413500D03*
Y1429700D03*
X328000Y1381500D03*
Y1374000D03*
X327500Y1368500D03*
X273500Y1403500D03*
X307500Y1389000D03*
X273500Y1431500D03*
X287600Y1448000D03*
X279650D03*
X299600D03*
X291600D03*
X326500Y1437700D03*
X311600Y1448000D03*
X303600D03*
X301800Y1722100D03*
X265500Y1722000D03*
X283500D03*
X297000Y1752000D03*
X302000D03*
X312559Y1986626D03*
X292559D03*
X272559D03*
X390018Y5500D03*
X350018D03*
X370018D03*
X382000Y98000D03*
X358000Y64000D03*
X344500Y71750D03*
X360750Y124000D03*
X369000Y294000D03*
X397000Y380250D03*
X375200Y371250D03*
X349870Y348870D03*
X375200Y429250D03*
X350137Y451250D03*
X336000Y570580D03*
Y578600D03*
X332500Y593000D03*
Y601000D03*
X368700Y803750D03*
X388250Y803300D03*
X375200Y858250D03*
X379372Y880728D03*
X374200Y1174750D03*
X400700Y1237500D03*
X375200Y1229750D03*
X356247Y1644123D03*
X348257Y1644132D03*
X385250Y1673000D03*
X379000Y1736000D03*
X351750Y1755500D03*
X343750D03*
X383000Y1736300D03*
Y1728700D03*
X375700Y1727750D03*
X392559Y1986626D03*
X372559D03*
X352559D03*
X332559D03*
X470018Y5500D03*
X410018D03*
X430018D03*
X450018D03*
X405500Y277500D03*
X405000Y289000D03*
X425879Y1721724D03*
X425500Y1713750D03*
X472559Y1986626D03*
X452559D03*
X432559D03*
X412559D03*
X530018Y5500D03*
X510018D03*
X490018D03*
X547659Y1560537D03*
X542159D03*
Y1566037D03*
X547659D03*
X492559Y1986626D03*
X512559D03*
X532559D03*
X590018Y5500D03*
X570018D03*
X550018D03*
X610018D03*
X552559Y1986626D03*
X572559D03*
X592559D03*
X612559D03*
X670018Y5500D03*
X650018D03*
X630018D03*
X690018D03*
X661500Y650500D03*
X634200Y1561200D03*
Y1565700D03*
X639700Y1561200D03*
Y1565700D03*
X646200Y1561200D03*
Y1565700D03*
X651700Y1561200D03*
Y1565700D03*
X632559Y1986626D03*
X652559D03*
X672559D03*
X692559D03*
X750018Y5500D03*
X730018D03*
X710018D03*
X753500Y1662000D03*
Y1666500D03*
X759000Y1662000D03*
Y1666500D03*
X765500Y1662000D03*
Y1666500D03*
X712559Y1986626D03*
X732559D03*
X752559D03*
X810018Y5500D03*
X790018D03*
X770018D03*
X830018D03*
X832500Y171000D03*
X824500D03*
X816500D03*
X813350Y369250D03*
X782500Y648000D03*
X813000Y1585750D03*
X808500Y1621500D03*
X814000D03*
Y1626000D03*
X808500D03*
X814000Y1630500D03*
X808500D03*
X771000Y1662000D03*
Y1666500D03*
X815000Y1785000D03*
X772559Y1986626D03*
X792559D03*
X812559D03*
X832559D03*
X890018Y5500D03*
X870018D03*
X850018D03*
X910018D03*
X885531Y164804D03*
X896441Y147203D03*
X844000Y190000D03*
X866961Y162539D03*
X901441Y244842D03*
X872941Y223745D03*
Y228145D03*
X844050Y337300D03*
X872941Y274138D03*
Y278538D03*
Y293036D03*
Y297436D03*
Y311934D03*
Y316334D03*
X895547Y552715D03*
X857735Y553465D03*
X883781Y564519D03*
X872941Y629257D03*
X876500Y648000D03*
X872941Y633657D03*
Y679650D03*
Y684050D03*
Y698548D03*
Y702948D03*
X846200Y743300D03*
X872941Y717446D03*
Y721846D03*
X883781Y970031D03*
X895547Y958227D03*
X857623Y958977D03*
X876500Y1053500D03*
X872941Y1034769D03*
Y1039169D03*
Y1085162D03*
Y1089562D03*
Y1104060D03*
Y1108460D03*
Y1122958D03*
Y1127358D03*
X844600Y1148700D03*
X883219Y1373504D03*
X895647Y1363738D03*
X857688Y1364488D03*
X872941Y1440281D03*
Y1444681D03*
Y1490674D03*
Y1495074D03*
X845600Y1554300D03*
X872941Y1509572D03*
Y1513972D03*
Y1528470D03*
Y1532870D03*
X895547Y1769250D03*
X883781Y1781054D03*
X876000Y1864000D03*
X872941Y1845793D03*
Y1850193D03*
Y1896186D03*
Y1900586D03*
Y1915084D03*
Y1919484D03*
Y1933982D03*
Y1938382D03*
X852559Y1986626D03*
X872559D03*
X896546Y1986566D03*
X912559Y1986626D03*
X844700Y1945200D03*
X950018Y5500D03*
X930018D03*
X970018D03*
X926347Y160000D03*
Y164453D03*
X926365Y569965D03*
Y565500D03*
X926477Y971000D03*
Y975477D03*
X926300Y1380988D03*
Y1376500D03*
X959000Y1631000D03*
Y1657000D03*
Y1675000D03*
X926400Y1782000D03*
Y1786500D03*
X932559Y1986626D03*
X952559D03*
X972559D03*
X1031902Y43616D03*
Y23616D03*
X1030018Y5500D03*
X1010018D03*
X990018D03*
X1031902Y63616D03*
Y103616D03*
Y83616D03*
Y143616D03*
Y123616D03*
Y163616D03*
Y183616D03*
Y263616D03*
Y223616D03*
Y203616D03*
Y243616D03*
Y303616D03*
Y283616D03*
Y323616D03*
Y403616D03*
Y383616D03*
Y363616D03*
Y343616D03*
Y483616D03*
Y443616D03*
Y423616D03*
Y463616D03*
Y523616D03*
Y503616D03*
Y543616D03*
Y623616D03*
Y603616D03*
Y583616D03*
Y563616D03*
Y683616D03*
Y663616D03*
Y643616D03*
Y763616D03*
Y743616D03*
Y723616D03*
Y703616D03*
Y843616D03*
Y823616D03*
Y803616D03*
Y783616D03*
Y903616D03*
Y883616D03*
Y863616D03*
Y983616D03*
Y963616D03*
Y943616D03*
Y923616D03*
Y1063616D03*
Y1043616D03*
Y1023616D03*
Y1003616D03*
Y1123616D03*
Y1103616D03*
Y1083616D03*
Y1143616D03*
Y1183616D03*
Y1163616D03*
Y1203616D03*
Y1283616D03*
Y1263616D03*
Y1243616D03*
Y1223616D03*
Y1343616D03*
Y1323616D03*
Y1303616D03*
Y1363616D03*
Y1383616D03*
X991602Y1622500D03*
X1031902Y1785969D03*
Y1745969D03*
Y1725969D03*
Y1765969D03*
Y1865969D03*
Y1845969D03*
Y1805969D03*
Y1825969D03*
Y1925969D03*
Y1885969D03*
Y1905969D03*
Y1965969D03*
Y1945969D03*
X992559Y1986626D03*
X1012559D03*
X1031902Y1985969D03*
G54D11*
X38800Y1810100D03*
X22100Y1802800D03*
X38317Y1804491D03*
X34900Y1807200D03*
X35100Y1813000D03*
X26500Y1805200D03*
X26600Y1810600D03*
X26300Y1815000D03*
X30800Y1805300D03*
Y1810500D03*
X17500Y1801900D03*
X22000Y1814100D03*
Y1809100D03*
X17500Y1806900D03*
Y1811900D03*
Y1816500D03*
X7600Y1855000D03*
X17500Y1827500D03*
X22600Y1825200D03*
X17500Y1832500D03*
X22500Y1830000D03*
X17500Y1837500D03*
X22500Y1835000D03*
X17500Y1842500D03*
X22500Y1840000D03*
X17500Y1847500D03*
X22500Y1845000D03*
X17500Y1852500D03*
X22500Y1850000D03*
X17500Y1857500D03*
X22500Y1855000D03*
Y1865000D03*
X17500Y1867500D03*
X22500Y1860000D03*
X12500Y1845000D03*
Y1850000D03*
Y1855000D03*
Y1840000D03*
X17500Y1872500D03*
X22500Y1870000D03*
X12500D03*
X935000Y1425000D03*
X984900Y1430400D03*
X953800Y1424900D03*
X945000Y1425000D03*
X935000Y1455000D03*
Y1475000D03*
Y1445000D03*
Y1465000D03*
Y1435000D03*
X945000Y1475000D03*
X955000D03*
X965000D03*
X945000Y1465000D03*
X955000D03*
X965000D03*
X945000Y1455000D03*
X955000D03*
X965000D03*
X945000Y1445000D03*
X955000D03*
X965000D03*
X945000Y1435000D03*
X955000D03*
X965000D03*
Y1495000D03*
X955000D03*
X935000Y1485000D03*
Y1495000D03*
X945000D03*
Y1485000D03*
X955000D03*
X965000D03*
X975000Y1495000D03*
Y1485000D03*
Y1475000D03*
Y1465000D03*
Y1455000D03*
Y1445000D03*
Y1435000D03*
X965000Y1525000D03*
X955000D03*
X945000D03*
Y1516000D03*
X955000D03*
X965000D03*
X935000Y1555000D03*
X945000D03*
X955000D03*
X965000D03*
X935000Y1575000D03*
Y1565000D03*
X945000Y1575000D03*
X955000D03*
X965000D03*
Y1565000D03*
X955000D03*
X945000D03*
X935000Y1545000D03*
Y1535000D03*
Y1525000D03*
Y1516000D03*
X965000Y1545000D03*
X955000D03*
X945000D03*
Y1535000D03*
X955000D03*
X965000D03*
X975000Y1565000D03*
Y1575000D03*
Y1525000D03*
Y1535000D03*
Y1545000D03*
Y1555000D03*
X935000Y1505000D03*
X955000D03*
X945000D03*
X965000D03*
Y1605000D03*
X935000Y1595000D03*
Y1585000D03*
X945000Y1595000D03*
X955000D03*
X965000D03*
Y1585000D03*
X955000D03*
X945000D03*
X975000Y1595000D03*
Y1605000D03*
Y1585000D03*
X990600Y1427100D03*
X995000Y1425000D03*
X1005000D03*
G54D12*
X393500Y422000D03*
Y852000D03*
X396637Y1176000D03*
X379500Y1673750D03*
G54D13*
G01X85427Y239715D02*
Y234166D01*
X81507Y230246D01*
X80153D01*
G01X60306Y212338D02*
X65699Y206945D01*
X99045D01*
X100400Y208300D01*
G01D02*
Y210626D01*
X93892Y217134D01*
X91566D01*
X80153Y228547D01*
Y230246D01*
G01Y635758D02*
Y621247D01*
X95900Y605500D01*
G01X80153Y635758D02*
X69283D01*
X62426Y628901D01*
Y607740D01*
G01X80153Y635758D02*
X81258D01*
X85223Y639723D01*
Y645227D01*
G01X77750Y1056750D02*
Y1043539D01*
X81689Y1039600D01*
G01D02*
X86189Y1035100D01*
Y1021511D01*
X96500Y1011200D01*
G01X64037Y1016654D02*
Y1021948D01*
X81689Y1039600D01*
G01X80600Y1848900D02*
X84500Y1852800D01*
Y1865500D01*
X103129Y1884129D01*
X112366D01*
G01Y1883985D02*
Y1884129D01*
G01D02*
X117371D01*
X137500Y1864000D01*
X148000D01*
G01X156800Y816000D02*
Y818700D01*
X133000Y842500D01*
X126800D01*
G01X206000Y1788000D02*
Y1835500D01*
X185000Y1856500D01*
Y1860280D01*
X178390Y1866890D01*
X173095D01*
G01X148000Y1864000D02*
X153800D01*
X158800Y1869000D01*
X170985D01*
X173095Y1866890D01*
G01X425500Y1713750D02*
Y1643500D01*
G01X425879Y1721724D02*
Y1714129D01*
X425500Y1713750D01*
G01X782500Y648000D02*
X664000D01*
X661500Y650500D01*
G01X813350Y369250D02*
X810500Y366400D01*
Y358100D01*
X831300Y337300D01*
X844050D01*
G01X845600Y1554300D02*
Y1555900D01*
X815750Y1585750D01*
G01D02*
X813000D01*
G01X883781Y1781054D02*
X876536D01*
X867532Y1772050D01*
X824050D01*
X815000Y1781100D01*
Y1785000D01*
G01X913346Y167366D02*
Y237466D01*
X909212Y241600D01*
X904683D01*
X901441Y244842D01*
G01X908300Y162320D02*
X913346Y167366D01*
G01X844050Y337300D02*
X849000D01*
X858400Y327900D01*
X879414D01*
X889846Y317468D01*
Y256437D01*
X901441Y244842D01*
G01X926365Y565500D02*
X913900D01*
X901115Y552715D01*
X895547D01*
G01X857735Y553465D02*
X862965D01*
X874019Y564519D01*
X883781D01*
G01D02*
Y560719D01*
X891785Y552715D01*
X895547D01*
G01X876500Y648000D02*
X885300D01*
X890600Y653300D01*
Y729600D01*
X871800Y748400D01*
X851300D01*
X846200Y743300D01*
G01X926477Y971000D02*
X913800D01*
X901027Y958227D01*
X895547D01*
G01X883781Y970031D02*
X868677D01*
X857623Y958977D01*
G01X883781Y970031D02*
Y966719D01*
X892273Y958227D01*
X895547D01*
G01X876500Y1053500D02*
X885600D01*
X888900Y1056800D01*
Y1138700D01*
X873800Y1153800D01*
X849700D01*
X844600Y1148700D01*
G01X895647Y1363738D02*
X889035D01*
X883219Y1369554D01*
Y1373504D01*
G01D02*
X874406D01*
X865390Y1364488D01*
X857688D01*
G01X895647Y1363738D02*
X899338D01*
X912100Y1376500D01*
X926300D01*
G01X883781Y1781054D02*
Y1779397D01*
X893928Y1769250D01*
X895547D01*
G01X926400Y1782000D02*
X916700D01*
X903950Y1769250D01*
X895547D01*
G01X844700Y1945200D02*
X884162D01*
X888729Y1940633D01*
Y1866829D01*
X885900Y1864000D01*
X876000D01*
G01X926365Y569965D02*
Y565500D01*
G01X926477Y975477D02*
Y971000D01*
G01X926300Y1376500D02*
Y1380988D01*
G01X926400Y1782000D02*
Y1786500D01*
G54D14*
G01X-90900Y-277455D02*
Y-294955D01*
X-82166D01*
G01X-69033Y-283289D02*
Y-294955D01*
G01Y-278622D02*
X-69470Y-278330D01*
Y-277747D01*
X-69033Y-277455D01*
X-68596Y-277747D01*
Y-278330D01*
X-69033Y-278622D01*
G01X-54590Y-299330D02*
X-53061Y-300497D01*
X-51315Y-300788D01*
X-49787Y-300497D01*
X-48476Y-299039D01*
X-47603Y-296997D01*
Y-283289D01*
G01Y-285622D02*
X-48476Y-284455D01*
X-49787Y-283580D01*
X-51315Y-283289D01*
X-53061Y-283872D01*
X-54153Y-285038D01*
X-55027Y-287080D01*
X-55463Y-289122D01*
X-55245Y-290872D01*
X-54371Y-292914D01*
X-53061Y-294372D01*
X-51315Y-294955D01*
X-50005Y-294663D01*
X-48476Y-293497D01*
X-47603Y-292331D01*
G01X-37745Y-294955D02*
Y-277455D01*
G01Y-285913D02*
X-36653Y-284455D01*
X-35561Y-283580D01*
X-33815Y-283289D01*
X-32505Y-283580D01*
X-30976Y-284747D01*
X-30321Y-286497D01*
Y-294955D01*
G01X-16533Y-277455D02*
Y-294955D01*
G01X-19590Y-283289D02*
X-13476D01*
G01X-2745Y-294955D02*
Y-283289D01*
G01Y-286205D02*
X-1871Y-284747D01*
X-561Y-283580D01*
X1185Y-283289D01*
X2713Y-283580D01*
X4024Y-284747D01*
X4679Y-286788D01*
Y-294955D01*
G01X18467Y-283289D02*
Y-294955D01*
G01Y-278622D02*
X18030Y-278330D01*
Y-277747D01*
X18467Y-277455D01*
X18904Y-277747D01*
Y-278330D01*
X18467Y-278622D01*
G01X32255Y-294955D02*
Y-283289D01*
G01Y-286205D02*
X33129Y-284747D01*
X34439Y-283580D01*
X36185Y-283289D01*
X37713Y-283580D01*
X39024Y-284747D01*
X39679Y-286788D01*
Y-294955D01*
G01X50410Y-299330D02*
X51939Y-300497D01*
X53685Y-300788D01*
X55213Y-300497D01*
X56524Y-299039D01*
X57397Y-296997D01*
Y-283289D01*
G01Y-285622D02*
X56524Y-284455D01*
X55213Y-283580D01*
X53685Y-283289D01*
X51939Y-283872D01*
X50847Y-285038D01*
X49973Y-287080D01*
X49537Y-289122D01*
X49755Y-290872D01*
X50629Y-292914D01*
X51939Y-294372D01*
X53685Y-294955D01*
X54995Y-294663D01*
X56524Y-293497D01*
X57397Y-292331D01*
G01X84100Y-294955D02*
Y-277455D01*
X89340D01*
X91087Y-278330D01*
X92397Y-280372D01*
X92834Y-282705D01*
X92397Y-285038D01*
X91305Y-286788D01*
X89340Y-287664D01*
X84100D01*
G01X101164Y-294955D02*
Y-277455D01*
X105530D01*
X107277Y-278330D01*
X108587Y-279497D01*
X109679Y-281246D01*
X110552Y-283289D01*
X110770Y-286205D01*
X110552Y-289122D01*
X109679Y-291164D01*
X108587Y-292914D01*
X107277Y-294080D01*
X105530Y-294955D01*
X101164D01*
G01X119100D02*
Y-277455D01*
X124340D01*
X126087Y-278330D01*
X127397Y-280372D01*
X127834Y-282705D01*
X127397Y-285038D01*
X126305Y-286788D01*
X124340Y-287664D01*
X119100D01*
G01X142713Y-285622D02*
X143587Y-284747D01*
X144242Y-283289D01*
X144679Y-281246D01*
X144242Y-279497D01*
X143369Y-278330D01*
X141840Y-277455D01*
X135945D01*
Y-294955D01*
X143150D01*
X144679Y-293789D01*
X145552Y-292038D01*
X145989Y-289997D01*
X145552Y-287955D01*
X144242Y-286205D01*
X142713Y-285622D01*
X135945D01*
G01X171600Y-294955D02*
Y-277455D01*
X176840D01*
X178587Y-278330D01*
X179897Y-280372D01*
X180334Y-282705D01*
X179897Y-285038D01*
X178805Y-286788D01*
X176840Y-287664D01*
X171600D01*
G01X188008Y-277455D02*
X193467Y-294955D01*
X198926Y-277455D01*
G01X210967D02*
Y-294955D01*
G01X205945Y-277455D02*
X215989D01*
G01X21540Y-249955D02*
Y-232455D01*
X27217Y-247038D01*
X32894Y-232455D01*
Y-249955D01*
G01X44717D02*
X43407Y-249663D01*
X42097Y-248497D01*
X41223Y-246455D01*
X40787Y-244122D01*
X41223Y-241788D01*
X42097Y-239747D01*
X43407Y-238580D01*
X44717Y-238289D01*
X46027Y-238580D01*
X47337Y-239747D01*
X48210Y-241788D01*
X48429Y-244122D01*
X48210Y-246455D01*
X47337Y-248497D01*
X46027Y-249663D01*
X44717Y-249955D01*
G01X66147Y-232455D02*
Y-249955D01*
G01Y-247331D02*
X65274Y-248789D01*
X63963Y-249663D01*
X62435Y-249955D01*
X60689Y-249372D01*
X59379Y-247914D01*
X58505Y-246164D01*
X58287Y-244122D01*
X58505Y-242080D01*
X59379Y-240330D01*
X60689Y-238872D01*
X62435Y-238289D01*
X63963Y-238580D01*
X65055Y-239164D01*
X66147Y-240330D01*
G01X76442Y-242080D02*
X83429D01*
X82774Y-240038D01*
X81682Y-238872D01*
X80154Y-238289D01*
X78625Y-238580D01*
X77315Y-239455D01*
X76442Y-241497D01*
X76005Y-243247D01*
Y-244997D01*
X76442Y-246747D01*
X77534Y-248497D01*
X78844Y-249663D01*
X80372Y-249955D01*
X81900Y-249372D01*
X83429Y-247622D01*
G01X97217Y-249955D02*
Y-232455D01*
G01X252500Y-249955D02*
Y-232455D01*
X257740D01*
X259487Y-233330D01*
X260797Y-235372D01*
X261234Y-237705D01*
X260797Y-240038D01*
X259705Y-241788D01*
X257740Y-242664D01*
X252500D01*
G01X279170Y-233914D02*
X277860Y-233038D01*
X276332Y-232455D01*
X274585D01*
X272620Y-233330D01*
X271092Y-234788D01*
X270000Y-236539D01*
X269127Y-239455D01*
X268908Y-242080D01*
X269345Y-244705D01*
X270000Y-246455D01*
X271310Y-248205D01*
X272839Y-249372D01*
X274367Y-249955D01*
X275895D01*
X277424Y-249372D01*
X278734Y-248497D01*
X279826Y-247331D01*
G01X293613Y-240622D02*
X294487Y-239747D01*
X295142Y-238289D01*
X295579Y-236246D01*
X295142Y-234497D01*
X294269Y-233330D01*
X292740Y-232455D01*
X286845D01*
Y-249955D01*
X294050D01*
X295579Y-248789D01*
X296452Y-247038D01*
X296889Y-244997D01*
X296452Y-242955D01*
X295142Y-241205D01*
X293613Y-240622D01*
X286845D01*
G01X302817Y-255788D02*
X315917D01*
G01X321845Y-249955D02*
Y-232455D01*
X331889Y-249955D01*
Y-232455D01*
G01X344367Y-249955D02*
X342620Y-249663D01*
X341092Y-248497D01*
X339782Y-246747D01*
X338908Y-244705D01*
X338472Y-242372D01*
Y-240038D01*
X338908Y-237705D01*
X339782Y-235663D01*
X341092Y-233914D01*
X342620Y-232747D01*
X344367Y-232455D01*
X346113Y-232747D01*
X347642Y-233914D01*
X348952Y-235663D01*
X349826Y-237705D01*
X350262Y-240038D01*
Y-242372D01*
X349826Y-244705D01*
X348952Y-246747D01*
X347642Y-248497D01*
X346113Y-249663D01*
X344367Y-249955D01*
G01X265617Y-294955D02*
Y-277455D01*
X262997Y-280955D01*
G01Y-294955D02*
X268237D01*
G01X278314Y-292331D02*
X279623Y-293789D01*
X281152Y-294663D01*
X283117Y-294955D01*
X285082Y-294372D01*
X286610Y-293205D01*
X287702Y-291164D01*
X287920Y-288830D01*
X287484Y-286497D01*
X286392Y-285038D01*
X284863Y-283872D01*
X283335Y-283580D01*
X281807Y-283872D01*
X279842Y-285038D01*
X280497Y-277455D01*
X286392D01*
G01X296469Y-287664D02*
X297997Y-285622D01*
X299307Y-284455D01*
X301054Y-283872D01*
X302582Y-284455D01*
X303674Y-285622D01*
X304547Y-287372D01*
X304765Y-289413D01*
X304547Y-291164D01*
X303674Y-292914D01*
X302363Y-294372D01*
X300835Y-294955D01*
X299089Y-294372D01*
X297560Y-292622D01*
X296687Y-289997D01*
X296469Y-287080D01*
X296905Y-283289D01*
X297560Y-281246D01*
X298652Y-279205D01*
X300180Y-277747D01*
X301709Y-277455D01*
X303237Y-278038D01*
X304329Y-279497D01*
G01X313969Y-287664D02*
X315497Y-285622D01*
X316807Y-284455D01*
X318554Y-283872D01*
X320082Y-284455D01*
X321174Y-285622D01*
X322047Y-287372D01*
X322265Y-289413D01*
X322047Y-291164D01*
X321174Y-292914D01*
X319863Y-294372D01*
X318335Y-294955D01*
X316589Y-294372D01*
X315060Y-292622D01*
X314187Y-289997D01*
X313969Y-287080D01*
X314405Y-283289D01*
X315060Y-281246D01*
X316152Y-279205D01*
X317680Y-277747D01*
X319209Y-277455D01*
X320737Y-278038D01*
X321829Y-279497D01*
G01X331905Y-292914D02*
X333434Y-294372D01*
X335180Y-294955D01*
X336927Y-294372D01*
X338455Y-292622D01*
X339547Y-289997D01*
X339984Y-287372D01*
Y-284164D01*
X339547Y-281539D01*
X338455Y-279205D01*
X337145Y-278038D01*
X335617Y-277455D01*
X333870Y-278038D01*
X332560Y-279205D01*
X331687Y-280955D01*
X331250Y-283289D01*
X331687Y-285330D01*
X332779Y-287372D01*
X334089Y-288539D01*
X335617Y-288830D01*
X337363Y-288247D01*
X338674Y-286788D01*
X339984Y-284164D01*
G01X395208Y-232455D02*
X400667Y-249955D01*
X406126Y-232455D01*
G01X422534Y-249955D02*
X413800D01*
Y-232455D01*
X422534D01*
G01X419040Y-240913D02*
X413800D01*
G01X431300Y-249955D02*
Y-232455D01*
X436759D01*
X438505Y-233330D01*
X439597Y-234497D01*
X440034Y-236830D01*
X439597Y-239164D01*
X438287Y-240622D01*
X436759Y-241497D01*
X431300D01*
G01X436759D02*
X440034Y-249955D01*
G01X453167Y-250538D02*
X452730Y-250247D01*
Y-249663D01*
X453167Y-249372D01*
X453604Y-249663D01*
Y-250247D01*
X453167Y-250538D01*
G01X426917Y-294955D02*
Y-277455D01*
X424297Y-280955D01*
G01Y-294955D02*
X429537D01*
G01X528750Y-232455D02*
Y-249955D01*
X537484D01*
G01X554547D02*
Y-238289D01*
G01Y-240330D02*
X553674Y-239164D01*
X552363Y-238580D01*
X550835Y-238289D01*
X549307Y-238872D01*
X547997Y-240038D01*
X547123Y-241788D01*
X546687Y-244122D01*
X547123Y-246455D01*
X547997Y-248205D01*
X549307Y-249372D01*
X550835Y-249955D01*
X552363Y-249663D01*
X553674Y-248789D01*
X554547Y-247622D01*
G01X563532Y-255205D02*
X564842Y-255788D01*
X566589Y-255205D01*
X567680Y-254039D01*
X568554Y-252580D01*
X569863Y-247914D01*
X572702Y-238289D01*
G01X565715D02*
X569863Y-247914D01*
G01X582342Y-242080D02*
X589329D01*
X588674Y-240038D01*
X587582Y-238872D01*
X586054Y-238289D01*
X584525Y-238580D01*
X583215Y-239455D01*
X582342Y-241497D01*
X581905Y-243247D01*
Y-244997D01*
X582342Y-246747D01*
X583434Y-248497D01*
X584744Y-249663D01*
X586272Y-249955D01*
X587800Y-249372D01*
X589329Y-247622D01*
G01X600060Y-249955D02*
Y-238289D01*
G01Y-240622D02*
X601152Y-239455D01*
X602244Y-238580D01*
X603772Y-238289D01*
X604863Y-238580D01*
X606174Y-239455D01*
G01X555000Y-277455D02*
Y-294955D01*
X563734D01*
G01X572064Y-291455D02*
X573373Y-293497D01*
X575120Y-294663D01*
X577085Y-294955D01*
X578832Y-294663D01*
X580579Y-293205D01*
X581670Y-291455D01*
X581889Y-289705D01*
X581452Y-287664D01*
X579924Y-286205D01*
X578395Y-285622D01*
X576430D01*
G01X578395D02*
X579705Y-284747D01*
X580797Y-283289D01*
X581234Y-281539D01*
X580797Y-279788D01*
X579705Y-278330D01*
X577740Y-277455D01*
X575775Y-277747D01*
X573810Y-278914D01*
G01X670864Y-249955D02*
Y-232455D01*
X675230D01*
X676977Y-233330D01*
X678287Y-234497D01*
X679379Y-236246D01*
X680252Y-238289D01*
X680470Y-241205D01*
X680252Y-244122D01*
X679379Y-246164D01*
X678287Y-247914D01*
X676977Y-249080D01*
X675230Y-249955D01*
X670864D01*
G01X689892Y-242080D02*
X696879D01*
X696224Y-240038D01*
X695132Y-238872D01*
X693604Y-238289D01*
X692075Y-238580D01*
X690765Y-239455D01*
X689892Y-241497D01*
X689455Y-243247D01*
Y-244997D01*
X689892Y-246747D01*
X690984Y-248497D01*
X692294Y-249663D01*
X693822Y-249955D01*
X695350Y-249372D01*
X696879Y-247622D01*
G01X707392Y-247914D02*
X708484Y-249080D01*
X710012Y-249955D01*
X711322D01*
X712632Y-249372D01*
X713505Y-248497D01*
X713942Y-247331D01*
X713724Y-245580D01*
X712850Y-244705D01*
X708920Y-242955D01*
X708047Y-240913D01*
X708484Y-239455D01*
X709357Y-238580D01*
X710667Y-238289D01*
X711977Y-238580D01*
X713287Y-239455D01*
G01X728167Y-238289D02*
Y-249955D01*
G01Y-233622D02*
X727730Y-233330D01*
Y-232747D01*
X728167Y-232455D01*
X728604Y-232747D01*
Y-233330D01*
X728167Y-233622D01*
G01X742610Y-254330D02*
X744139Y-255497D01*
X745885Y-255788D01*
X747413Y-255497D01*
X748724Y-254039D01*
X749597Y-251997D01*
Y-238289D01*
G01Y-240622D02*
X748724Y-239455D01*
X747413Y-238580D01*
X745885Y-238289D01*
X744139Y-238872D01*
X743047Y-240038D01*
X742173Y-242080D01*
X741737Y-244122D01*
X741955Y-245872D01*
X742829Y-247914D01*
X744139Y-249372D01*
X745885Y-249955D01*
X747195Y-249663D01*
X748724Y-248497D01*
X749597Y-247331D01*
G01X759455Y-249955D02*
Y-238289D01*
G01Y-241205D02*
X760329Y-239747D01*
X761639Y-238580D01*
X763385Y-238289D01*
X764913Y-238580D01*
X766224Y-239747D01*
X766879Y-241788D01*
Y-249955D01*
G01X777392Y-242080D02*
X784379D01*
X783724Y-240038D01*
X782632Y-238872D01*
X781104Y-238289D01*
X779575Y-238580D01*
X778265Y-239455D01*
X777392Y-241497D01*
X776955Y-243247D01*
Y-244997D01*
X777392Y-246747D01*
X778484Y-248497D01*
X779794Y-249663D01*
X781322Y-249955D01*
X782850Y-249372D01*
X784379Y-247622D01*
G01X795110Y-249955D02*
Y-238289D01*
G01Y-240622D02*
X796202Y-239455D01*
X797294Y-238580D01*
X798822Y-238289D01*
X799913Y-238580D01*
X801224Y-239455D01*
G01X660367Y-277455D02*
X663423Y-294955D01*
X666917Y-277455D01*
X670410Y-294955D01*
X673467Y-277455D01*
G01X680050Y-294955D02*
Y-277455D01*
X685290D01*
X687037Y-278330D01*
X688347Y-280372D01*
X688784Y-282705D01*
X688347Y-285038D01*
X687255Y-286788D01*
X685290Y-287664D01*
X680050D01*
G01X697332Y-294955D02*
Y-277455D01*
G01X706502D02*
Y-294955D01*
G01Y-286205D02*
X697332D01*
G01X716579Y-289122D02*
X722255D01*
G01X732769Y-294955D02*
Y-277455D01*
X741065D01*
G01X738009Y-285913D02*
X732769D01*
G01X750050Y-277455D02*
Y-294955D01*
X758784D01*
G01X771917D02*
X770170Y-294663D01*
X768642Y-293497D01*
X767332Y-291747D01*
X766458Y-289705D01*
X766022Y-287372D01*
Y-285038D01*
X766458Y-282705D01*
X767332Y-280663D01*
X768642Y-278914D01*
X770170Y-277747D01*
X771917Y-277455D01*
X773663Y-277747D01*
X775192Y-278914D01*
X776502Y-280663D01*
X777376Y-282705D01*
X777812Y-285038D01*
Y-287372D01*
X777376Y-289705D01*
X776502Y-291747D01*
X775192Y-293497D01*
X773663Y-294663D01*
X771917Y-294955D01*
G01X785050D02*
Y-277455D01*
X790509D01*
X792255Y-278330D01*
X793347Y-279497D01*
X793784Y-281830D01*
X793347Y-284164D01*
X792037Y-285622D01*
X790509Y-286497D01*
X785050D01*
G01X790509D02*
X793784Y-294955D01*
G01X801458D02*
X806917Y-277455D01*
X812376Y-294955D01*
G01X810410Y-288830D02*
X803423D01*
G01X841867Y-294955D02*
Y-277455D01*
X839247Y-280955D01*
G01Y-294955D02*
X844487D01*
G01X859367D02*
Y-277455D01*
X856747Y-280955D01*
G01Y-294955D02*
X861987D01*
G01X872937Y-295538D02*
X880797Y-277455D01*
G01X894367Y-294955D02*
Y-277455D01*
X891747Y-280955D01*
G01Y-294955D02*
X896987D01*
G01X907719Y-287664D02*
X909247Y-285622D01*
X910557Y-284455D01*
X912304Y-283872D01*
X913832Y-284455D01*
X914924Y-285622D01*
X915797Y-287372D01*
X916015Y-289413D01*
X915797Y-291164D01*
X914924Y-292914D01*
X913613Y-294372D01*
X912085Y-294955D01*
X910339Y-294372D01*
X908810Y-292622D01*
X907937Y-289997D01*
X907719Y-287080D01*
X908155Y-283289D01*
X908810Y-281246D01*
X909902Y-279205D01*
X911430Y-277747D01*
X912959Y-277455D01*
X914487Y-278038D01*
X915579Y-279497D01*
G01X925437Y-295538D02*
X933297Y-277455D01*
G01X942719Y-280372D02*
X944029Y-278622D01*
X945557Y-277747D01*
X947304Y-277455D01*
X949487Y-278038D01*
X951015Y-279497D01*
X951452Y-281246D01*
X951234Y-282997D01*
X950360Y-284455D01*
X945994Y-287372D01*
X944029Y-289413D01*
X942719Y-292331D01*
X942282Y-294955D01*
X951452D01*
G01X964367Y-277455D02*
X962620Y-278038D01*
X961310Y-279497D01*
X960437Y-281246D01*
X959782Y-283580D01*
X959564Y-286205D01*
X959782Y-288830D01*
X960437Y-291164D01*
X961310Y-292914D01*
X962620Y-294372D01*
X964367Y-294955D01*
X966113Y-294372D01*
X967424Y-292914D01*
X968297Y-291164D01*
X968952Y-288830D01*
X969170Y-286205D01*
X968952Y-283580D01*
X968297Y-281246D01*
X967424Y-279497D01*
X966113Y-278038D01*
X964367Y-277455D01*
G01X981867Y-294955D02*
Y-277455D01*
X979247Y-280955D01*
G01Y-294955D02*
X984487D01*
G01X995219Y-287664D02*
X996747Y-285622D01*
X998057Y-284455D01*
X999804Y-283872D01*
X1001332Y-284455D01*
X1002424Y-285622D01*
X1003297Y-287372D01*
X1003515Y-289413D01*
X1003297Y-291164D01*
X1002424Y-292914D01*
X1001113Y-294372D01*
X999585Y-294955D01*
X997839Y-294372D01*
X996310Y-292622D01*
X995437Y-289997D01*
X995219Y-287080D01*
X995655Y-283289D01*
X996310Y-281246D01*
X997402Y-279205D01*
X998930Y-277747D01*
X1000459Y-277455D01*
X1001987Y-278038D01*
X1003079Y-279497D01*
G01X889564Y-249955D02*
Y-232455D01*
X893930D01*
X895677Y-233330D01*
X896987Y-234497D01*
X898079Y-236246D01*
X898952Y-238289D01*
X899170Y-241205D01*
X898952Y-244122D01*
X898079Y-246164D01*
X896987Y-247914D01*
X895677Y-249080D01*
X893930Y-249955D01*
X889564D01*
G01X915797D02*
Y-238289D01*
G01Y-240330D02*
X914924Y-239164D01*
X913613Y-238580D01*
X912085Y-238289D01*
X910557Y-238872D01*
X909247Y-240038D01*
X908373Y-241788D01*
X907937Y-244122D01*
X908373Y-246455D01*
X909247Y-248205D01*
X910557Y-249372D01*
X912085Y-249955D01*
X913613Y-249663D01*
X914924Y-248789D01*
X915797Y-247622D01*
G01X929367Y-232455D02*
Y-249955D01*
G01X926310Y-238289D02*
X932424D01*
G01X943592Y-242080D02*
X950579D01*
X949924Y-240038D01*
X948832Y-238872D01*
X947304Y-238289D01*
X945775Y-238580D01*
X944465Y-239455D01*
X943592Y-241497D01*
X943155Y-243247D01*
Y-244997D01*
X943592Y-246747D01*
X944684Y-248497D01*
X945994Y-249663D01*
X947522Y-249955D01*
X949050Y-249372D01*
X950579Y-247622D01*
G01X129000Y255500D02*
X131900Y258400D01*
X188900D01*
X224851Y294351D01*
X248068D01*
X259037Y305320D01*
X321220D01*
X342251Y326351D01*
Y341251D01*
X349870Y348870D01*
G01X196000Y1070300D02*
X142600D01*
X139300Y1067000D01*
G01X379372Y880728D02*
X375591Y884509D01*
Y892909D01*
X198200Y1070300D01*
X196000D01*
G01X350137Y451250D02*
X348265Y453122D01*
X338428D01*
X297300Y494250D01*
Y505017D01*
G54D15*
G01X20000Y607620D02*
X20901Y608521D01*
X31472D01*
X34903Y607916D01*
X38423Y605452D01*
X42153Y600120D01*
X42298Y599300D01*
X42569Y597759D01*
X42572Y597746D01*
X41971Y596888D01*
X42310Y594968D01*
X43167Y594368D01*
X43506Y592448D01*
X42905Y591590D01*
X43244Y589670D01*
X44101Y589070D01*
X44440Y587150D01*
X43839Y586292D01*
X44178Y584372D01*
X45035Y583772D01*
X48565Y563759D01*
X47964Y562902D01*
X48303Y560982D01*
X49160Y560381D01*
X49499Y558461D01*
X48898Y557604D01*
X49237Y555684D01*
X50094Y555083D01*
X50433Y553163D01*
X50432Y553162D01*
X50433D01*
X25481Y411644D01*
X35991Y351992D01*
X102859Y256495D01*
X111192Y209224D01*
X113970Y193468D01*
X113971D01*
X113370Y192611D01*
X113709Y190691D01*
X114566Y190090D01*
X114905Y188170D01*
X114304Y187312D01*
X114643Y185392D01*
X115500Y184792D01*
X115502Y184791D01*
Y184790D01*
X115501D01*
X119671Y161136D01*
X117896Y151064D01*
X115384Y147477D01*
X113334Y146041D01*
X106484Y144833D01*
X101000D01*
X99500Y146333D01*
G01X20000Y610820D02*
X20899Y609921D01*
X31595D01*
X35452Y609241D01*
X39429Y606458D01*
X43479Y600669D01*
X51855Y553163D01*
X26903Y411644D01*
X37316Y352541D01*
X104184Y257044D01*
X121093Y161136D01*
X119221Y150515D01*
X116390Y146471D01*
X113883Y144716D01*
X107977Y143674D01*
X106607Y143433D01*
X101000D01*
X99500Y141933D01*
G01X20000Y620218D02*
X20902Y621120D01*
X25461D01*
X28699Y620549D01*
X37595Y614320D01*
X38714Y612723D01*
X38532Y611692D01*
X39651Y610095D01*
X40681Y609913D01*
X45527Y602994D01*
X54264Y553449D01*
X39119Y467559D01*
X65630Y317232D01*
X106347Y259084D01*
X124803Y154403D01*
X124203Y153546D01*
X124541Y151626D01*
X125398Y151025D01*
X125737Y149105D01*
X125137Y148248D01*
X125475Y146328D01*
X126332Y145727D01*
X126671Y143807D01*
X126071Y142950D01*
X126409Y141030D01*
X127266Y140429D01*
X127605Y138509D01*
X127005Y137652D01*
X127344Y135732D01*
X128201Y135131D01*
X128200D01*
X129742Y126390D01*
X127369Y112937D01*
X124784Y109246D01*
X123753Y109064D01*
X122635Y107467D01*
X122817Y106436D01*
X121698Y104839D01*
X120667Y104657D01*
X119549Y103060D01*
X119731Y102029D01*
X118612Y100432D01*
X112058Y95844D01*
X104087Y94439D01*
X101001D01*
X99500Y95940D01*
G01X20000Y623418D02*
X20898Y622520D01*
X25584D01*
X29248Y621874D01*
X38601Y615326D01*
X46852Y603543D01*
X55686Y553449D01*
X40541Y467559D01*
X66955Y317781D01*
X107672Y259633D01*
X131164Y126390D01*
X128694Y112388D01*
X119618Y99426D01*
X112607Y94519D01*
X104210Y93039D01*
X100999D01*
X99500Y91540D01*
G01Y77042D02*
X101164Y75378D01*
X104020D01*
X106878Y75883D01*
X107479Y76740D01*
X109399Y77078D01*
X110256Y76478D01*
X115331Y77373D01*
X125808Y84727D01*
X128681Y88827D01*
X129103Y91221D01*
X128503Y92078D01*
X128841Y93998D01*
X129698Y94599D01*
X130037Y96519D01*
X129437Y97376D01*
X129775Y99296D01*
X130632Y99897D01*
X130971Y101817D01*
X130371Y102674D01*
X130709Y104594D01*
X131566Y105195D01*
X131905Y107115D01*
X131305Y107972D01*
X131644Y109892D01*
X132501Y110493D01*
X134475Y121689D01*
X134477Y121688D01*
X109744Y261951D01*
X69253Y319764D01*
X69262Y319787D01*
X69255Y319803D01*
X68726Y321117D01*
X68630Y321663D01*
X42820Y468033D01*
X58073Y554529D01*
X46204Y621839D01*
X44190Y624715D01*
X41271Y626760D01*
X40240Y626578D01*
X38643Y627697D01*
X38461Y628727D01*
X36864Y629846D01*
X35833Y629664D01*
X34236Y630783D01*
X34054Y631813D01*
X32457Y632932D01*
X32458D01*
X27756Y633761D01*
X20944D01*
X20000Y632817D01*
G01X99500Y551845D02*
X101145Y550200D01*
X104380D01*
X106200Y548380D01*
Y546006D01*
X104926Y543822D01*
X102580Y542414D01*
X98100Y541068D01*
X85924Y543524D01*
X83124Y545509D01*
X81031Y548778D01*
X79432Y553574D01*
X82530Y571128D01*
X84305Y573663D01*
X92168Y579169D01*
X96429Y585255D01*
X100029Y605671D01*
X89927Y662962D01*
X88500Y665000D01*
X86353Y666504D01*
X72450Y668957D01*
X43029Y663771D01*
X38778Y660795D01*
X28247Y658915D01*
X20902D01*
X20000Y658013D01*
G01X99500Y547445D02*
X100855Y548800D01*
X103800D01*
X104800Y547800D01*
Y546385D01*
X103897Y544838D01*
X102009Y543705D01*
X98033Y542510D01*
X86492Y544839D01*
X84156Y546494D01*
X82305Y549386D01*
X80873Y553680D01*
X81212Y555600D01*
X82069Y556200D01*
X82408Y558121D01*
X81808Y558978D01*
X82147Y560898D01*
X83004Y561498D01*
X83343Y563419D01*
X82743Y564276D01*
X83855Y570579D01*
X85311Y572657D01*
X93174Y578163D01*
X97754Y584706D01*
X99544Y594857D01*
X100402Y595457D01*
X100740Y597377D01*
X100140Y598235D01*
X100479Y600155D01*
X101336Y600756D01*
X101674Y602676D01*
X101074Y603533D01*
X101451Y605671D01*
X91252Y663511D01*
X89506Y666006D01*
X86902Y667829D01*
X72448Y670380D01*
X63672Y668832D01*
X62815Y669433D01*
X60895Y669094D01*
X60294Y668237D01*
X58374Y667898D01*
X57517Y668499D01*
X55597Y668160D01*
X54996Y667303D01*
X53076Y666964D01*
X52219Y667564D01*
X50299Y667226D01*
X49698Y666369D01*
X47778Y666030D01*
X46921Y666630D01*
X45001Y666292D01*
X44400Y665435D01*
X42480Y665096D01*
X38228Y662119D01*
X28123Y660315D01*
X20898D01*
X20000Y661213D01*
G01Y670612D02*
X20901Y671513D01*
X28246D01*
X37741Y673187D01*
X38598Y672587D01*
X40519Y672925D01*
X41119Y673782D01*
X43039Y674121D01*
X43897Y673521D01*
X45817Y673859D01*
X46417Y674716D01*
X48338Y675055D01*
X49195Y674455D01*
X51115Y674793D01*
X51716Y675650D01*
X53636Y675989D01*
X53976Y675942D01*
X88685Y669821D01*
X90344Y668660D01*
X92000Y667500D01*
X93071Y665970D01*
X99732Y628204D01*
X106501Y589826D01*
X108677Y586718D01*
X108495Y585688D01*
X109613Y584090D01*
X110644Y583908D01*
X111762Y582311D01*
X111580Y581281D01*
X112698Y579683D01*
X113729Y579501D01*
X114847Y577904D01*
X114666Y576874D01*
X115784Y575276D01*
X116815Y575094D01*
X117933Y573497D01*
X121229Y554804D01*
X116726Y529281D01*
X116405Y527462D01*
X115548Y526862D01*
X115209Y524941D01*
X115809Y524084D01*
X115442Y522003D01*
X116928Y513572D01*
X115708Y506654D01*
X113500Y503500D01*
X109786Y500900D01*
X104402Y499951D01*
X101001D01*
X99500Y501452D01*
G01Y497052D02*
X100999Y498551D01*
X104525D01*
X110335Y499575D01*
X114506Y502494D01*
X117033Y506105D01*
X118350Y513572D01*
X116864Y522003D01*
X122651Y554804D01*
X119258Y574046D01*
X107826Y590375D01*
X94396Y666519D01*
X93147Y668303D01*
X93148Y668304D01*
X93006Y668506D01*
X89234Y671146D01*
X54194Y677326D01*
X53610Y677407D01*
X28123Y672913D01*
X20899D01*
X20000Y673812D01*
G01X99500Y482554D02*
X101001Y481053D01*
X104941D01*
X107670Y481534D01*
X109267Y482653D01*
X109449Y483683D01*
X111046Y484802D01*
X112077Y484620D01*
X120033Y490193D01*
X121152Y491790D01*
X120970Y492821D01*
X122088Y494418D01*
X123119Y494600D01*
X124238Y496197D01*
X124056Y497228D01*
X125174Y498825D01*
X126205Y499007D01*
X127324Y500604D01*
X127142Y501635D01*
X128260Y503232D01*
X129291Y503414D01*
X130614Y505303D01*
X132261Y514647D01*
X121666Y574737D01*
X110205Y591107D01*
X96773Y667254D01*
X94500Y670499D01*
X94501D01*
X94500Y670500D01*
X90162Y673539D01*
X51260Y680398D01*
X50403Y679798D01*
X48483Y680136D01*
X47882Y680993D01*
X45962Y681332D01*
X45105Y680732D01*
X43185Y681070D01*
X42584Y681927D01*
X40664Y682266D01*
X39807Y681666D01*
X37887Y682005D01*
X37286Y682862D01*
X30196Y684112D01*
X20902D01*
X20000Y683210D01*
G01Y686410D02*
X20898Y685512D01*
X30319D01*
X90711Y674864D01*
X95029Y671839D01*
X95304Y671647D01*
X95506Y671506D01*
X98098Y667803D01*
X111530Y591656D01*
X122991Y575286D01*
X133683Y514647D01*
X131939Y504754D01*
X121039Y489187D01*
X108219Y480209D01*
X105064Y479653D01*
X100999D01*
X99500Y478154D01*
G01Y72642D02*
X100836Y73978D01*
X104143D01*
X115881Y76047D01*
X126810Y83716D01*
X130006Y88278D01*
X135898Y121694D01*
X111069Y262500D01*
X70534Y320377D01*
X70080Y321504D01*
X70009Y321906D01*
X44242Y468033D01*
X59495Y554529D01*
X47529Y622388D01*
X45196Y625721D01*
X33007Y634257D01*
X27879Y635161D01*
X20856D01*
X20000Y636017D01*
G01X99500Y463656D02*
X101000Y462156D01*
X104607D01*
X108278Y462804D01*
X113855Y466708D01*
X114036Y467738D01*
X115634Y468857D01*
X116665Y468675D01*
X118262Y469793D01*
X124038Y478042D01*
X123857Y479072D01*
X124975Y480670D01*
X126006Y480851D01*
X127125Y482448D01*
X126943Y483479D01*
X128062Y485076D01*
X129092Y485258D01*
X130211Y486855D01*
X130029Y487886D01*
X131148Y489483D01*
X132178Y489665D01*
X133297Y491262D01*
X136779Y511009D01*
X125349Y575834D01*
X113950Y592113D01*
X100290Y669572D01*
X97456Y673619D01*
X76760Y688113D01*
X43894Y693907D01*
X43036Y693307D01*
X41116Y693645D01*
X40516Y694503D01*
X38595Y694841D01*
X37738Y694241D01*
X35818Y694580D01*
X35218Y695437D01*
X33297Y695776D01*
X32440Y695175D01*
X30520Y695514D01*
X29919Y696371D01*
X27999Y696710D01*
X20901D01*
X20000Y695809D01*
G01X99500Y459256D02*
X101000Y460756D01*
X104730D01*
X108827Y461479D01*
X119268Y468787D01*
X134622Y490713D01*
X138201Y511009D01*
X126674Y576384D01*
X115275Y592662D01*
X115159Y593326D01*
X101615Y670121D01*
X98462Y674625D01*
X77309Y689438D01*
X28123Y698110D01*
X20899D01*
X20000Y699009D01*
G01X99500Y58244D02*
X101000Y56744D01*
X105174D01*
X110183Y57627D01*
X112177Y59024D01*
X112346Y59993D01*
X114108Y61228D01*
X115078Y61055D01*
X116843Y62291D01*
X119911Y66672D01*
X119721Y67741D01*
X120955Y69504D01*
X122025Y69691D01*
X123259Y71454D01*
X123069Y72523D01*
X124303Y74286D01*
X125373Y74473D01*
X126607Y76236D01*
X126417Y77305D01*
X127651Y79068D01*
X128721Y79255D01*
X129955Y81018D01*
X129765Y82087D01*
X130999Y83850D01*
X132069Y84037D01*
X133306Y85802D01*
X133914Y89251D01*
X133241Y90208D01*
X133616Y92327D01*
X134573Y92995D01*
X134948Y95113D01*
X134275Y96070D01*
X134650Y98189D01*
X135607Y98857D01*
X139070Y118489D01*
X113264Y264844D01*
X72808Y322622D01*
X47028Y468820D01*
X62077Y554159D01*
X48620Y630473D01*
X41972Y639968D01*
X34558Y645160D01*
X28000Y646316D01*
X20901D01*
X20000Y645415D01*
G01X99500Y53844D02*
X101000Y55344D01*
X105297D01*
X110732Y56302D01*
X117849Y61285D01*
X134631Y85253D01*
X140492Y118490D01*
X114589Y265393D01*
X74134Y323170D01*
X48450Y468820D01*
X63499Y554159D01*
X49945Y631022D01*
X42978Y640974D01*
X35107Y646485D01*
X28123Y647716D01*
X20899D01*
X20000Y648615D01*
G01X144595Y223745D02*
X143095Y225245D01*
X139031D01*
X134658Y226016D01*
X130190Y229143D01*
X124540Y237215D01*
X118252Y272871D01*
X76500Y332500D01*
X73199Y351219D01*
X76752Y371361D01*
X84535Y382475D01*
X94353Y389350D01*
X96817Y391075D01*
X155354Y401397D01*
X163833Y407334D01*
X165591Y409843D01*
X167029Y418001D01*
X163148Y440005D01*
X154512Y452337D01*
X133233Y573012D01*
X118564Y593962D01*
X104847Y671779D01*
X97482Y682298D01*
X69312Y702025D01*
X31818Y708635D01*
X28000Y709308D01*
X20901D01*
X20000Y708407D01*
G01X144595Y228145D02*
X143095Y226645D01*
X139154D01*
X135207Y227341D01*
X131196Y230149D01*
X125865Y237764D01*
X119577Y273420D01*
X77825Y333049D01*
X74621Y351219D01*
X78077Y370812D01*
X85541Y381469D01*
X95156Y388202D01*
X97366Y389750D01*
X155903Y400072D01*
X164839Y406328D01*
X166916Y409294D01*
X168451Y418001D01*
X164473Y440554D01*
X155837Y452886D01*
X134559Y573561D01*
X134289Y573946D01*
X119889Y594511D01*
X106172Y672328D01*
X98488Y683304D01*
X69861Y703350D01*
X28123Y710708D01*
X20899D01*
X20000Y711607D01*
G01X144595Y274138D02*
X143094Y275639D01*
X139570D01*
X129163Y277474D01*
X110250Y290716D01*
X79821Y334175D01*
X76825Y351170D01*
X79978Y369045D01*
X88000Y380500D01*
X98058Y387542D01*
X156503Y397851D01*
X166491Y404845D01*
X169259Y408798D01*
X170882Y418000D01*
X166749Y441432D01*
X158016Y453904D01*
X136718Y574664D01*
X136267Y575309D01*
X135805Y575969D01*
X122270Y595300D01*
X108489Y673433D01*
X87248Y703765D01*
X72558Y714052D01*
X36027Y720492D01*
X32459Y721121D01*
X28000Y721907D01*
X20901D01*
X20000Y721006D01*
G01Y724206D02*
X20899Y723307D01*
X28123D01*
X73107Y715377D01*
X88254Y704771D01*
X109814Y673982D01*
X123595Y595849D01*
X138044Y575213D01*
X159341Y454453D01*
X168074Y441981D01*
X172304Y418000D01*
X170584Y408249D01*
X167497Y403839D01*
X157052Y396526D01*
X98607Y386217D01*
X89006Y379494D01*
X81303Y368496D01*
X78247Y351170D01*
X81146Y334724D01*
X111256Y291722D01*
X129712Y278799D01*
X139693Y277039D01*
X143096D01*
X144595Y278538D01*
G01X20000Y752502D02*
X20901Y753403D01*
X28000D01*
X85175Y713370D01*
X112002Y675059D01*
X125773Y596944D01*
X140089Y576492D01*
X161652Y454924D01*
X170591Y442157D01*
X174749Y418584D01*
X172810Y407585D01*
X168598Y401569D01*
X158090Y394212D01*
X99189Y383833D01*
X90356Y377649D01*
X83504Y367863D01*
X80531Y351004D01*
X80573Y350761D01*
X83000Y337000D01*
X99886Y312887D01*
X105392Y307381D01*
X116019Y299939D01*
X121796Y297576D01*
X130427Y296054D01*
X139031Y294537D01*
X143094D01*
X144595Y293036D01*
G01X20000Y755702D02*
X20899Y754803D01*
X28442D01*
X86181Y714376D01*
X113327Y675608D01*
X127098Y597493D01*
X141414Y577041D01*
X162977Y455473D01*
X171916Y442706D01*
X176171Y418584D01*
X174135Y407036D01*
X169604Y400563D01*
X158639Y392887D01*
X99738Y382508D01*
X91362Y376643D01*
X84829Y367314D01*
X81953Y351004D01*
X84325Y337549D01*
X100963Y313790D01*
X106295Y308458D01*
X116694Y301176D01*
X122187Y298929D01*
X139154Y295937D01*
X143096D01*
X144595Y297436D01*
G01Y311934D02*
X143095Y313434D01*
X139365D01*
X115621Y317620D01*
X90314Y335339D01*
X86000Y341500D01*
X84266Y351337D01*
X86886Y366195D01*
X93238Y375267D01*
X99838Y379887D01*
X159332Y390381D01*
X171462Y398875D01*
X176360Y405871D01*
X178705Y419167D01*
X174519Y442904D01*
X165312Y456053D01*
X143886Y577501D01*
X129369Y598236D01*
X115460Y677121D01*
X77501Y731340D01*
X28000Y766001D01*
X20901D01*
X20000Y765100D01*
G01X144595Y316334D02*
X143095Y314834D01*
X139488D01*
X116170Y318945D01*
X91320Y336345D01*
X87325Y342049D01*
X85688Y351339D01*
X88211Y365644D01*
X94244Y374261D01*
X100387Y378562D01*
X159881Y389056D01*
X172468Y397869D01*
X177685Y405322D01*
X180127Y419167D01*
X175844Y443453D01*
X166637Y456602D01*
X145211Y578050D01*
X130694Y598785D01*
X116785Y677670D01*
X78507Y732346D01*
X28442Y767401D01*
X20899D01*
X20000Y768300D01*
G01X99500Y957357D02*
X101000Y955857D01*
X105064D01*
X106797Y955552D01*
X109488Y953669D01*
X116281Y943968D01*
X118671Y930417D01*
X118672D01*
X121420Y914828D01*
X175729Y837263D01*
X178068Y824000D01*
X175915Y811791D01*
X168898Y801770D01*
X155563Y792433D01*
X97794Y782248D01*
X89415Y780771D01*
X75052Y783303D01*
X65791Y789787D01*
X52107Y809331D01*
X49900Y821845D01*
X46680Y826442D01*
X30105Y838049D01*
X27877Y838442D01*
X20901D01*
X20000Y837541D01*
G01Y840741D02*
X20899Y839842D01*
X28000D01*
X30654Y839374D01*
X32251Y838256D01*
X33282Y838437D01*
X34879Y837319D01*
X35061Y836288D01*
X36658Y835170D01*
X37689Y835351D01*
X39286Y834233D01*
X39468Y833202D01*
X41065Y832084D01*
X42096Y832266D01*
X43693Y831147D01*
X43875Y830116D01*
X47686Y827448D01*
X51225Y822394D01*
X53432Y809880D01*
X66797Y790793D01*
X75601Y784628D01*
X89415Y782193D01*
X97550Y783627D01*
X155014Y793758D01*
X167892Y802776D01*
X174590Y812340D01*
X176646Y824000D01*
X174404Y836714D01*
X120095Y914279D01*
X119756Y916199D01*
X118899Y916800D01*
X118560Y918720D01*
X119161Y919577D01*
X118822Y921498D01*
X117965Y922098D01*
X117626Y924018D01*
X118226Y924875D01*
X117887Y926796D01*
X117030Y927396D01*
X116692Y929316D01*
X117292Y930174D01*
X114956Y943419D01*
X111568Y948256D01*
X110538Y948438D01*
X109419Y950035D01*
X109601Y951066D01*
X108482Y952663D01*
X106248Y954227D01*
X104941Y954457D01*
X101000D01*
X99500Y952957D01*
G01X144595Y629257D02*
X143095Y630757D01*
X139031D01*
X136283Y631242D01*
X132968Y633563D01*
X126485Y642823D01*
X120226Y678321D01*
X54806Y771750D01*
X32715Y787218D01*
X28000Y788049D01*
X20902D01*
X20000Y787147D01*
G01X144595Y633657D02*
X143095Y632157D01*
X139154D01*
X136832Y632567D01*
X133974Y634569D01*
X127810Y643372D01*
X121551Y678870D01*
X55812Y772756D01*
X33264Y788543D01*
X28123Y789449D01*
X20898D01*
X20000Y790347D01*
G01X144595Y679650D02*
X143094Y681151D01*
X139570D01*
X131354Y682601D01*
X112766Y695615D01*
X47748Y788471D01*
X31195Y800061D01*
X27877Y800647D01*
X20901D01*
X20000Y799746D01*
G01X144595Y684050D02*
X143096Y682551D01*
X139693D01*
X131903Y683926D01*
X113772Y696621D01*
X48754Y789477D01*
X31744Y801386D01*
X28000Y802047D01*
X20899D01*
X20000Y802946D01*
G01Y812344D02*
X20902Y813246D01*
X27877D01*
X29587Y812944D01*
X41511Y804594D01*
X106209Y712193D01*
X118350Y703693D01*
X127148Y702143D01*
X134203Y700900D01*
X139031Y700049D01*
X143094D01*
X144595Y698548D01*
G01X20000Y815544D02*
X20898Y814646D01*
X28000D01*
X30136Y814269D01*
X42518Y805598D01*
X107215Y713199D01*
X118899Y705018D01*
X127391Y703522D01*
X133968Y702363D01*
X134446Y702279D01*
X139154Y701449D01*
X143096D01*
X144595Y702948D01*
G01Y717446D02*
X143095Y718946D01*
X139365D01*
X109258Y724252D01*
X87711Y745800D01*
X37261Y817850D01*
X35487Y820383D01*
X33713Y822915D01*
X30088Y825454D01*
X29536Y825551D01*
X27877Y825844D01*
X20901D01*
X20000Y824943D01*
G01X144595Y721846D02*
X143095Y720346D01*
X139488D01*
X109936Y725555D01*
X88788Y746703D01*
X38408Y818653D01*
X34719Y823921D01*
X30637Y826779D01*
X28000Y827244D01*
X20899D01*
X20000Y828143D01*
G01X872941Y223745D02*
X871441Y225245D01*
X867377D01*
X864764Y225706D01*
X858559Y230049D01*
X813576Y294292D01*
X343966Y623132D01*
X124012Y937173D01*
X118864Y966391D01*
X114755Y972264D01*
X102883Y979974D01*
X96129Y981410D01*
X82868Y978590D01*
X68828Y969471D01*
X62920Y960376D01*
X57466Y929449D01*
X40322Y904961D01*
X36356Y902185D01*
X32095Y901434D01*
X20901D01*
X20000Y900533D01*
G01X872941Y228145D02*
X871441Y226645D01*
X867500D01*
X865313Y227031D01*
X859565Y231055D01*
X814582Y295298D01*
X344972Y624138D01*
X125337Y937722D01*
X120190Y966940D01*
X115746Y973290D01*
X103428Y981290D01*
X96129Y982842D01*
X89207Y981370D01*
X82323Y979906D01*
X67815Y970484D01*
X61590Y960900D01*
X56141Y929998D01*
X39316Y905967D01*
X35807Y903510D01*
X31972Y902834D01*
X20899D01*
X20000Y903733D01*
G01X99500Y906964D02*
X101001Y905463D01*
X104525D01*
X110786Y904359D01*
X110787D01*
X136800Y886145D01*
X172201Y835587D01*
X174274Y823833D01*
X172500Y813770D01*
X165730Y804102D01*
X153847Y795782D01*
X90166Y784549D01*
X76081Y787034D01*
X68700Y792201D01*
X55986Y810360D01*
X51568Y835390D01*
X44561Y845397D01*
X39408Y849006D01*
X27877Y851041D01*
X20902D01*
X20000Y850139D01*
G01X99500Y902564D02*
X100999Y904063D01*
X104402D01*
X110237Y903034D01*
X111834Y901916D01*
X112016Y900885D01*
X113613Y899766D01*
X114644Y899948D01*
X116241Y898830D01*
X116423Y897799D01*
X118020Y896681D01*
X119051Y896862D01*
X120648Y895744D01*
X120830Y894713D01*
X122427Y893595D01*
X123458Y893776D01*
X135794Y885139D01*
X137930Y882088D01*
X137749Y881057D01*
X138867Y879460D01*
X139898Y879278D01*
X141016Y877681D01*
X140835Y876650D01*
X141953Y875053D01*
X142984Y874871D01*
X144102Y873274D01*
X143921Y872243D01*
X145039Y870646D01*
X146070Y870464D01*
X170876Y835038D01*
X172852Y823833D01*
X171175Y814319D01*
X164724Y805108D01*
X153298Y797107D01*
X90166Y785971D01*
X76630Y788359D01*
X69706Y793207D01*
X57311Y810909D01*
X52893Y835939D01*
X45567Y846403D01*
X39957Y850331D01*
X34500Y851294D01*
X33900Y852151D01*
X31980Y852490D01*
X31123Y851890D01*
X28000Y852441D01*
X20898D01*
X20000Y853339D01*
G01X872941Y274138D02*
X871440Y275639D01*
X867916D01*
X840295Y280509D01*
X346092Y626549D01*
X127596Y938595D01*
X121308Y974264D01*
X116675Y980878D01*
X79467Y1006928D01*
X75184Y1007684D01*
X71678D01*
X66927Y1006845D01*
X65035Y1005521D01*
X64831Y1005317D01*
X61204Y1000137D01*
X49867Y935840D01*
X39005Y920328D01*
X31936Y915380D01*
X24291Y914033D01*
X20901D01*
X20000Y913132D01*
G01X872941Y278538D02*
X871442Y277039D01*
X868039D01*
X840844Y281834D01*
X347098Y627555D01*
X128921Y939144D01*
X122633Y974813D01*
X117681Y981884D01*
X80016Y1008253D01*
X75307Y1009084D01*
X71555D01*
X66378Y1008170D01*
X64132Y1006598D01*
X63754Y1006220D01*
X59879Y1000686D01*
X48542Y936389D01*
X37999Y921334D01*
X31387Y916705D01*
X24168Y915433D01*
X20899D01*
X20000Y916332D01*
G01Y862738D02*
X20901Y863639D01*
X27877D01*
X40290Y861450D01*
X46751Y856922D01*
X53417Y847413D01*
X59754Y811477D01*
X71377Y794877D01*
X77862Y790337D01*
X89414Y788300D01*
X151989Y799331D01*
X163760Y807572D01*
X168517Y814367D01*
X170186Y823833D01*
X168286Y834606D01*
X151233Y858964D01*
X113544Y885353D01*
X106669Y886565D01*
X101001D01*
X99500Y888066D01*
G01X20000Y865938D02*
X20899Y865039D01*
X28000D01*
X40839Y862775D01*
X47757Y857928D01*
X54742Y847962D01*
X55081Y846042D01*
X55938Y845441D01*
X56277Y843521D01*
X55676Y842664D01*
X56015Y840743D01*
X56872Y840143D01*
X57211Y838223D01*
X56611Y837366D01*
X56949Y835445D01*
X57807Y834845D01*
X58145Y832925D01*
X57545Y832067D01*
X61079Y812026D01*
X72383Y795883D01*
X78411Y791662D01*
X89414Y789722D01*
X151440Y800656D01*
X162754Y808578D01*
X167192Y814916D01*
X168764Y823833D01*
X166961Y834057D01*
X150227Y857958D01*
X145409Y861332D01*
X144378Y861150D01*
X142781Y862268D01*
X142599Y863299D01*
X126216Y874770D01*
X125185Y874589D01*
X123588Y875707D01*
X123406Y876738D01*
X121809Y877856D01*
X120778Y877675D01*
X119181Y878793D01*
X118999Y879824D01*
X117402Y880942D01*
X116371Y880760D01*
X114774Y881879D01*
X114592Y882910D01*
X112995Y884028D01*
X106546Y885165D01*
X100999D01*
X99500Y883666D01*
G01Y869168D02*
X100768Y867900D01*
X104100D01*
X107192Y864808D01*
X114552Y855575D01*
X122516Y849996D01*
X152483Y844711D01*
X160570Y839051D01*
X164612Y833276D01*
X166387Y823213D01*
X165201Y816487D01*
X161006Y810494D01*
X149755Y802617D01*
X90419Y792153D01*
X78951Y794175D01*
X73888Y797719D01*
X65314Y809965D01*
X56775Y858393D01*
X50510Y867342D01*
X41145Y873900D01*
X27877Y876238D01*
X20902D01*
X20000Y875336D01*
G01X99500Y864768D02*
X101232Y866500D01*
X103520D01*
X106146Y863874D01*
X113583Y854544D01*
X121967Y848671D01*
X151934Y843386D01*
X159564Y838045D01*
X163287Y832727D01*
X164965Y823213D01*
X163876Y817036D01*
X160000Y811500D01*
X149206Y803942D01*
X144304Y803078D01*
X143447Y803678D01*
X141527Y803339D01*
X140926Y802482D01*
X139006Y802143D01*
X138149Y802744D01*
X136229Y802405D01*
X135628Y801548D01*
X133708Y801209D01*
X132850Y801809D01*
X130930Y801471D01*
X130330Y800613D01*
X90419Y793575D01*
X79500Y795500D01*
X74894Y798725D01*
X66639Y810514D01*
X62172Y835847D01*
X62773Y836704D01*
X62434Y838624D01*
X61577Y839225D01*
X61238Y841145D01*
X61839Y842003D01*
X61500Y843923D01*
X60643Y844523D01*
X60304Y846443D01*
X60905Y847301D01*
X60566Y849221D01*
X59709Y849821D01*
X59370Y851741D01*
X59970Y852599D01*
X59632Y854519D01*
X58774Y855119D01*
X58100Y858942D01*
X51516Y868348D01*
X41694Y875225D01*
X28000Y877638D01*
X20898D01*
X20000Y878536D01*
G01X872941Y629257D02*
X871441Y630757D01*
X867075D01*
X802126Y676232D01*
X320988Y761073D01*
X214730Y835472D01*
X139548Y942845D01*
X133231Y978656D01*
X114535Y1005360D01*
X114534Y1005361D01*
X114533D01*
X103918Y1065609D01*
X69553Y1114684D01*
X31556Y1141283D01*
X25340Y1142379D01*
X20901D01*
X20000Y1141478D01*
G01X872941Y633657D02*
X871441Y632157D01*
X867517D01*
X802675Y677557D01*
X321537Y762398D01*
X215736Y836478D01*
X140873Y943394D01*
X134556Y979205D01*
X115860Y1005909D01*
X115859Y1005911D01*
X115857Y1005914D01*
X115858D01*
X105243Y1066158D01*
X70559Y1115690D01*
X32105Y1142608D01*
X25463Y1143779D01*
X20899D01*
X20000Y1144678D01*
G01X872941Y293036D02*
X871440Y294537D01*
X867377D01*
X813360Y304063D01*
X349031Y629193D01*
X131006Y940563D01*
X124845Y975495D01*
X101139Y1009353D01*
X91776Y1062434D01*
X85293Y1071694D01*
X41792Y1102151D01*
X28000Y1104584D01*
X20901D01*
X20000Y1103683D01*
G01X872941Y297436D02*
X871442Y295937D01*
X867500D01*
X813909Y305388D01*
X350037Y630199D01*
X132331Y941112D01*
X126170Y976044D01*
X102464Y1009902D01*
X93101Y1062984D01*
X86298Y1072700D01*
X42341Y1103477D01*
X28123Y1105984D01*
X20899D01*
X20000Y1106883D01*
G01Y1116281D02*
X20902Y1117183D01*
X27417D01*
X41495Y1114699D01*
X80356Y1087489D01*
X94794Y1066868D01*
X104663Y1010888D01*
X128682Y976586D01*
X134916Y941242D01*
X351115Y632490D01*
X786246Y327797D01*
X867711Y313434D01*
X871441D01*
X872941Y311934D01*
G01X20000Y1119481D02*
X20898Y1118583D01*
X27540D01*
X42044Y1116025D01*
X81360Y1088497D01*
X96119Y1067418D01*
X105988Y1011437D01*
X130007Y977135D01*
X136241Y941791D01*
X352121Y633496D01*
X786795Y329122D01*
X867834Y314834D01*
X871441D01*
X872941Y316334D01*
G01X144595Y1034769D02*
X143095Y1036269D01*
X139154D01*
X135304Y1036948D01*
X131270Y1037660D01*
X126500Y1041000D01*
X123752Y1044925D01*
X116512Y1085985D01*
X53400Y1176123D01*
X30157Y1192392D01*
X30155Y1192393D01*
X28000Y1192773D01*
X20901D01*
X20000Y1191872D01*
G01X144595Y1039169D02*
X143095Y1037669D01*
X139277D01*
X131819Y1038985D01*
X127506Y1042006D01*
X125077Y1045474D01*
X117837Y1086534D01*
X54406Y1177129D01*
X30706Y1193718D01*
X28123Y1194173D01*
X20899D01*
X20000Y1195072D01*
G01Y1154076D02*
X20902Y1154978D01*
X25068D01*
X33453Y1156760D01*
X40111Y1155584D01*
X57570Y1143363D01*
X106259Y1073829D01*
X118079Y1006796D01*
X136609Y980333D01*
X142942Y944426D01*
X217415Y838066D01*
X322419Y764539D01*
X831574Y674764D01*
X867793Y681151D01*
X871440D01*
X872941Y679650D01*
G01X20000Y1157276D02*
X20898Y1156378D01*
X24920D01*
X33428Y1158187D01*
X40660Y1156909D01*
X58576Y1144369D01*
X107584Y1074378D01*
X119404Y1007345D01*
X137756Y981136D01*
Y981137D01*
X137934Y980882D01*
X144267Y944975D01*
X218421Y839072D01*
X322968Y765864D01*
X831573Y676186D01*
X867670Y682551D01*
X871442D01*
X872941Y684050D01*
G01X144595Y1085162D02*
X143094Y1086663D01*
X139693D01*
X128328Y1088669D01*
X113153Y1099294D01*
X43823Y1198309D01*
X35712Y1203989D01*
X27877Y1205371D01*
X20901D01*
X20000Y1204470D01*
G01X144595Y1089562D02*
X143096Y1088063D01*
X139816D01*
X128877Y1089994D01*
X114159Y1100300D01*
X44829Y1199315D01*
X36261Y1205314D01*
X28000Y1206771D01*
X20899D01*
X20000Y1207670D01*
G01X872941Y698548D02*
X871440Y700049D01*
X867231D01*
X840467Y705739D01*
X759072Y691386D01*
X323617Y768137D01*
X219986Y840702D01*
X146532Y945583D01*
X140123Y981961D01*
X140117Y981970D01*
X121630Y1008371D01*
X109107Y1079359D01*
X109108D01*
X56323Y1154734D01*
X49145Y1159395D01*
X45533Y1160162D01*
X41386Y1161042D01*
X32883Y1166997D01*
X29607Y1167576D01*
X20901D01*
X20000Y1166675D01*
G01X872941Y702948D02*
X871442Y701449D01*
X867379D01*
X840492Y707166D01*
X759072Y692808D01*
X324166Y769462D01*
X220992Y841708D01*
X147857Y946132D01*
X141448Y982510D01*
X141273Y982761D01*
Y982760D01*
X122955Y1008920D01*
X110433Y1079908D01*
Y1079909D01*
X57312Y1155763D01*
X49690Y1160711D01*
X41956Y1162353D01*
X33432Y1168322D01*
X29730Y1168976D01*
X20899D01*
X20000Y1169875D01*
G01Y1179273D02*
X20902Y1180175D01*
X25039D01*
X29772Y1179340D01*
X58579Y1159192D01*
X112496Y1082161D01*
Y1082160D01*
X125300Y1009557D01*
X128260Y1005330D01*
X134682Y996159D01*
X143708Y983270D01*
X149177Y952272D01*
X225716Y842943D01*
X328506Y770967D01*
X745309Y697504D01*
X866924Y718946D01*
X871441D01*
X872941Y717446D01*
G01X20000Y1182473D02*
X20898Y1181575D01*
X25162D01*
X30321Y1180666D01*
X59585Y1160198D01*
X113821Y1082710D01*
X126625Y1010106D01*
X145033Y983819D01*
X150502Y952821D01*
X226722Y843949D01*
X329055Y772292D01*
X745309Y698926D01*
X866801Y720346D01*
X871441D01*
X872941Y721846D01*
G01X20000Y1261163D02*
X20901Y1262064D01*
X27877D01*
X34747Y1260853D01*
X40963Y1256499D01*
X46507Y1248585D01*
X53181Y1210727D01*
X59789Y1201289D01*
X79382Y1187569D01*
X91000Y1185520D01*
X153766Y1196588D01*
X177481Y1192406D01*
X263155Y1132420D01*
X838044Y1031075D01*
X867500Y1036269D01*
X871441D01*
X872941Y1034769D01*
G01X20000Y1264363D02*
X20899Y1263464D01*
X28000D01*
X35296Y1262178D01*
X41969Y1257505D01*
X47832Y1249134D01*
X54506Y1211276D01*
X60795Y1202295D01*
X79931Y1188894D01*
X91000Y1186942D01*
X153766Y1198010D01*
X178030Y1193731D01*
X263704Y1133745D01*
X838044Y1032497D01*
X867377Y1037669D01*
X871441D01*
X872941Y1039169D01*
G01Y1085162D02*
X871440Y1086663D01*
X868039D01*
X706277Y1058140D01*
X264329Y1136048D01*
X178899Y1195863D01*
X153846Y1200280D01*
X91163Y1189226D01*
X80559Y1191097D01*
X62738Y1203575D01*
X57000Y1211772D01*
X49019Y1257036D01*
X40716Y1268891D01*
X34022Y1273579D01*
X27877Y1274663D01*
X20902D01*
X20000Y1273761D01*
G01X872941Y1089562D02*
X871442Y1088063D01*
X867916D01*
X706277Y1059562D01*
X264878Y1137373D01*
X179448Y1197188D01*
X153846Y1201702D01*
X91163Y1190648D01*
X81108Y1192422D01*
X63744Y1204581D01*
X58325Y1212321D01*
X50344Y1257585D01*
X41722Y1269897D01*
X34571Y1274904D01*
X28000Y1276063D01*
X20898D01*
X20000Y1276961D01*
G01X872941Y1104060D02*
X871440Y1105561D01*
X867500D01*
X662987Y1069500D01*
X265498Y1139586D01*
X180298Y1199242D01*
X153680Y1203936D01*
X91001Y1192883D01*
X81956Y1194477D01*
X65500Y1206000D01*
X60628Y1212958D01*
X50394Y1270996D01*
X44866Y1278890D01*
X34609Y1286074D01*
X27877Y1287261D01*
X20901D01*
X20000Y1286360D01*
G01X144595Y1104060D02*
X143094Y1105561D01*
X139154D01*
X131668Y1106881D01*
X96802Y1131296D01*
X40169Y1212181D01*
X33257Y1217021D01*
X27877Y1217970D01*
X20901D01*
X20000Y1217069D01*
G01X144595Y1108460D02*
X143096Y1106961D01*
X139277D01*
X132217Y1108206D01*
X97808Y1132302D01*
X41175Y1213187D01*
X33806Y1218346D01*
X28000Y1219370D01*
X20899D01*
X20000Y1220269D01*
G01X144595Y1122958D02*
X143095Y1124458D01*
X139611D01*
X121494Y1127653D01*
X88111Y1151028D01*
X47271Y1209354D01*
X42316Y1237453D01*
X36865Y1245238D01*
X31821Y1248770D01*
X27877Y1249466D01*
X20901D01*
X20000Y1248565D01*
G01X144595Y1127358D02*
X143095Y1125858D01*
X139734D01*
Y1125859D01*
X130887Y1127419D01*
X122043Y1128978D01*
X89117Y1152034D01*
X48596Y1209903D01*
X43641Y1238002D01*
X37871Y1246244D01*
X32370Y1250095D01*
X28000Y1250866D01*
X20899D01*
X20000Y1251765D01*
G01X99500Y1362869D02*
X100769Y1361600D01*
X103880D01*
X105400Y1360080D01*
Y1357448D01*
X103802Y1354554D01*
X97493Y1352189D01*
X77007Y1356696D01*
X65103Y1354719D01*
X61972Y1352529D01*
X61971Y1352528D01*
X50185Y1335694D01*
X50184Y1335695D01*
X50182Y1335692D01*
G02X49593Y1335103I-1966J1377D01*
G01X31667Y1322554D01*
X28000Y1321907D01*
X20901D01*
X20000Y1321006D01*
G01X99500Y1358469D02*
X101231Y1360200D01*
X103300D01*
X104000Y1359500D01*
Y1357810D01*
X102826Y1355685D01*
X97390Y1353646D01*
Y1353647D01*
X97389Y1353646D01*
X77044Y1358122D01*
X69863Y1356930D01*
X69012Y1357539D01*
X67088Y1357219D01*
X66480Y1356368D01*
X64556Y1356048D01*
X60965Y1353534D01*
X58294Y1349719D01*
X57264Y1349537D01*
X56146Y1347940D01*
X56327Y1346909D01*
X55209Y1345312D01*
X54178Y1345130D01*
X53060Y1343533D01*
X53241Y1342502D01*
X52123Y1340905D01*
X51092Y1340723D01*
X49974Y1339126D01*
X50155Y1338095D01*
X49037Y1336498D01*
G02X48791Y1336253I-818J575D01*
G01X44339Y1333136D01*
X43309Y1333318D01*
X41711Y1332200D01*
X41529Y1331169D01*
X39932Y1330051D01*
X38902Y1330232D01*
X37304Y1329114D01*
X37122Y1328083D01*
X35525Y1326965D01*
X34495Y1327146D01*
X32897Y1326028D01*
X32715Y1324997D01*
X31118Y1323879D01*
X27877Y1323307D01*
X20899D01*
X20000Y1324206D01*
G01X99500Y1312476D02*
X101001Y1310975D01*
X104402D01*
X108782Y1311747D01*
X112000Y1314000D01*
X113613Y1316303D01*
X114254Y1319939D01*
X113654Y1320796D01*
X113992Y1322716D01*
X114849Y1323317D01*
X115188Y1325237D01*
X112356Y1341298D01*
X117285Y1369265D01*
X115673Y1378410D01*
X114065Y1380706D01*
X104029Y1387731D01*
X95099Y1389306D01*
X89535Y1388325D01*
X82444Y1383360D01*
X82263Y1382330D01*
X80665Y1381211D01*
X79635Y1381393D01*
X78037Y1380275D01*
X77855Y1379244D01*
X76258Y1378125D01*
X75227Y1378307D01*
X73630Y1377189D01*
X73448Y1376158D01*
X71851Y1375040D01*
X70820Y1375221D01*
X69223Y1374103D01*
X50271Y1347037D01*
X47067Y1344794D01*
X46885Y1343763D01*
X45288Y1342644D01*
X44257Y1342826D01*
X42660Y1341708D01*
X42478Y1340677D01*
X40881Y1339559D01*
X39850Y1339740D01*
X38253Y1338622D01*
X38071Y1337591D01*
X36474Y1336473D01*
X35443Y1336654D01*
X33846Y1335536D01*
X28000Y1334505D01*
X20901D01*
X20000Y1333604D01*
G01X99500Y1308076D02*
X100999Y1309575D01*
X104525D01*
X109331Y1310422D01*
X113006Y1312994D01*
X114938Y1315754D01*
X116610Y1325237D01*
X113778Y1341298D01*
X118707Y1369265D01*
X116998Y1378959D01*
X115071Y1381712D01*
X104578Y1389056D01*
X95099Y1390728D01*
X88986Y1389650D01*
X68217Y1375109D01*
X49265Y1348043D01*
X41282Y1342452D01*
X33297Y1336861D01*
X27877Y1335905D01*
X20899D01*
X20000Y1336804D01*
G01X99500Y1293578D02*
X101095Y1291983D01*
X104408D01*
X109465Y1292875D01*
X109464D01*
X112500Y1295000D01*
X114633Y1298046D01*
X114972Y1299966D01*
X114405Y1300777D01*
X114744Y1302698D01*
X115555Y1303265D01*
X115894Y1305185D01*
X115327Y1305996D01*
X115666Y1307917D01*
X116477Y1308484D01*
X116816Y1310404D01*
X116249Y1311215D01*
X116588Y1313136D01*
X117399Y1313703D01*
X119330Y1324628D01*
X116208Y1342332D01*
X121046Y1369767D01*
X119134Y1380608D01*
X117421Y1383054D01*
X102641Y1393403D01*
X101610Y1393222D01*
X100013Y1394340D01*
X99831Y1395371D01*
X98234Y1396489D01*
X97203Y1396307D01*
X95606Y1397426D01*
X95424Y1398457D01*
X93827Y1399575D01*
X92796Y1399393D01*
X91199Y1400512D01*
X91017Y1401542D01*
X89420Y1402661D01*
X85750Y1403309D01*
X80276Y1402343D01*
X73540Y1397628D01*
X46119Y1358467D01*
X46291Y1357492D01*
X45172Y1355894D01*
X44197Y1355722D01*
X43079Y1354125D01*
X34796Y1348324D01*
X27667Y1347067D01*
X20865D01*
X20000Y1346202D01*
G01X99500Y1289178D02*
X100905Y1290583D01*
X104531D01*
X110014Y1291550D01*
X113506Y1293994D01*
X115958Y1297497D01*
X120752Y1324628D01*
X117630Y1342332D01*
X120006Y1355807D01*
X122425Y1369524D01*
Y1369523D01*
X122468Y1369767D01*
X120459Y1381157D01*
X118427Y1384060D01*
X89969Y1403986D01*
X85750Y1404731D01*
X79727Y1403668D01*
X72534Y1398634D01*
X42073Y1355131D01*
X34247Y1349649D01*
X27544Y1348467D01*
X20935D01*
X20000Y1349402D01*
G01X872941Y1108460D02*
X871442Y1106961D01*
X867377D01*
X662987Y1070922D01*
X266047Y1140911D01*
X180847Y1200567D01*
X153680Y1205358D01*
X91001Y1194305D01*
X82505Y1195802D01*
X66506Y1207006D01*
X61953Y1213507D01*
X51719Y1271545D01*
X45872Y1279896D01*
X35158Y1287399D01*
X28000Y1288661D01*
X20899D01*
X20000Y1289560D01*
G01X872941Y1122958D02*
X871441Y1124458D01*
X867834D01*
X620703Y1080882D01*
X266818Y1143255D01*
X182065Y1202598D01*
X153011Y1207721D01*
X90328Y1196667D01*
X83342Y1197900D01*
X68278Y1208446D01*
X64055Y1214479D01*
X52905Y1277705D01*
X46230Y1287237D01*
X28903Y1299370D01*
X26123Y1299860D01*
X20902D01*
X20000Y1298958D01*
G01X872941Y1127358D02*
X871441Y1125858D01*
X867711D01*
X620703Y1082304D01*
X267367Y1144580D01*
X182614Y1203923D01*
X153011Y1209143D01*
X90328Y1198089D01*
X83891Y1199225D01*
X69284Y1209452D01*
X65380Y1215028D01*
X54230Y1278254D01*
X47236Y1288243D01*
X29452Y1300695D01*
X26246Y1301260D01*
X20898D01*
X20000Y1302158D01*
G01X144595Y1440281D02*
X143095Y1441781D01*
X139154D01*
X86681Y1432529D01*
X63421Y1416244D01*
X34863Y1375459D01*
X31143Y1372855D01*
X28000Y1372301D01*
X20902D01*
X20000Y1371399D01*
G01X144595Y1444681D02*
X143095Y1443181D01*
X139031D01*
X86132Y1433854D01*
X62415Y1417250D01*
X33857Y1376465D01*
X30594Y1374180D01*
X27877Y1373701D01*
X20898D01*
X20000Y1374599D01*
G01X144595Y1490674D02*
X143094Y1492175D01*
X139570D01*
X89706Y1500967D01*
X82032Y1499614D01*
X72563Y1492983D01*
X67747Y1486105D01*
X54317Y1409950D01*
X42167Y1392598D01*
X32239Y1385646D01*
X28000Y1384899D01*
X20901D01*
X20000Y1383998D01*
G01X144595Y1495074D02*
X143096Y1493575D01*
X139693D01*
X89706Y1502389D01*
X81483Y1500939D01*
X71557Y1493989D01*
X66422Y1486654D01*
X52992Y1410499D01*
X41161Y1393604D01*
X31690Y1386971D01*
X27877Y1386299D01*
X20899D01*
X20000Y1387198D01*
G01X144595Y1509572D02*
X143094Y1511073D01*
X139154D01*
X134202Y1510200D01*
X126593Y1511542D01*
X80524Y1503417D01*
X70242Y1496218D01*
X63988Y1487285D01*
X50472Y1410673D01*
X46500Y1405000D01*
X38407Y1399333D01*
X28000Y1397497D01*
X20901D01*
X20000Y1396596D01*
G01X144595Y1513972D02*
X143096Y1512473D01*
X139031D01*
X134202Y1511622D01*
X126593Y1512964D01*
X79975Y1504742D01*
X69236Y1497224D01*
X62663Y1487834D01*
X49147Y1411222D01*
X45494Y1406006D01*
X37858Y1400658D01*
X27877Y1398897D01*
X20899D01*
X20000Y1399796D01*
G01X99500Y1274680D02*
X101089Y1273091D01*
X104103D01*
X107865Y1273755D01*
X112500Y1277000D01*
X116908Y1283295D01*
Y1283298D01*
X117247Y1285218D01*
X116646Y1286076D01*
X116985Y1287996D01*
X117842Y1288596D01*
X118181Y1290517D01*
X117581Y1291374D01*
X117919Y1293294D01*
X118777Y1293894D01*
X119115Y1295815D01*
X118515Y1296672D01*
X118854Y1298593D01*
X119711Y1299193D01*
X123669Y1321638D01*
X120115Y1341798D01*
X125032Y1369688D01*
X122709Y1382857D01*
X120589Y1385887D01*
X120588Y1385889D01*
X82382Y1412639D01*
X73954Y1414125D01*
X68473Y1413158D01*
X66198Y1411566D01*
X61973Y1405534D01*
X61635Y1403614D01*
X62202Y1402803D01*
X61864Y1400882D01*
X61053Y1400314D01*
X60715Y1398394D01*
X61282Y1397583D01*
X60944Y1395662D01*
X60133Y1395094D01*
X58742Y1387200D01*
X48194Y1372137D01*
X44957Y1369870D01*
X44785Y1368895D01*
X43187Y1367776D01*
X42213Y1367948D01*
X40616Y1366829D01*
X40444Y1365855D01*
X38847Y1364736D01*
X37872Y1364908D01*
X31299Y1360305D01*
X27877Y1359702D01*
X20901D01*
X20000Y1358801D01*
G01X99500Y1270280D02*
X100911Y1271691D01*
X104226D01*
X108414Y1272430D01*
X110986Y1274231D01*
X113506Y1275994D01*
X115851Y1279344D01*
X118055Y1282492D01*
X118233Y1282746D01*
X125091Y1321638D01*
X121537Y1341798D01*
X126454Y1369688D01*
X124035Y1383406D01*
X124034D01*
X121597Y1386892D01*
X82931Y1413964D01*
X73954Y1415547D01*
X67924Y1414483D01*
X65192Y1412572D01*
X60648Y1406083D01*
X57417Y1387749D01*
X47188Y1373143D01*
X30750Y1361630D01*
X27754Y1361102D01*
X20899D01*
X20000Y1362001D01*
G01X144595Y1528470D02*
X143095Y1529970D01*
X139488D01*
X102388Y1523428D01*
X67919Y1499293D01*
X60342Y1488470D01*
X51066Y1435868D01*
X35634Y1413836D01*
X31064Y1410636D01*
X28000Y1410096D01*
X20901D01*
X20000Y1409195D01*
G01X144595Y1532870D02*
X143095Y1531370D01*
X139365D01*
X101839Y1524753D01*
X66913Y1500299D01*
X59017Y1489019D01*
X49741Y1436417D01*
X34628Y1414842D01*
X30515Y1411961D01*
X27877Y1411496D01*
X20899D01*
X20000Y1412395D01*
G01X872941Y1440281D02*
X871441Y1441781D01*
X867058D01*
X801222Y1487880D01*
G03X800222Y1488294I-1434J-2048D01*
G01X178046Y1597999D01*
G03X177178I-434J-2462D01*
G01X93217Y1583196D01*
X48042Y1551569D01*
X39092Y1538786D01*
X29820Y1532293D01*
X24496Y1531355D01*
X20901D01*
X20000Y1530454D01*
G01X872941Y1444681D02*
X871441Y1443181D01*
X867500D01*
X802025Y1489027D01*
G03X800466Y1489673I-2237J-3194D01*
G01X178289Y1599379D01*
G03X176935I-677J-3841D01*
G01X92668Y1584521D01*
X47036Y1552575D01*
X38086Y1539792D01*
X29271Y1533618D01*
X24373Y1532755D01*
X20899D01*
X20000Y1533654D01*
G01X872941Y1490674D02*
X871440Y1492175D01*
X867916D01*
X833778Y1486180D01*
X177883Y1601837D01*
X177884D01*
G03X177536I-174J-985D01*
G01X91322Y1586633D01*
X31166Y1544511D01*
X28000Y1543953D01*
X20901D01*
X20000Y1543052D01*
G01X872941Y1495074D02*
X871442Y1493575D01*
X867794D01*
X833778Y1487602D01*
X178126Y1603216D01*
G03X177293I-416J-2363D01*
G01X90773Y1587958D01*
X30617Y1545836D01*
X27877Y1545353D01*
X20899D01*
X20000Y1546252D01*
G01X872941Y1509572D02*
X871440Y1511073D01*
X867377D01*
X791162Y1497657D01*
G02X789808I-677J3841D01*
G01X177513Y1605626D01*
G03X176645I-434J-2462D01*
G01X81011Y1588762D01*
X37366Y1558203D01*
X28000Y1556552D01*
X20902D01*
X20000Y1555650D01*
G01X872941Y1513972D02*
X871442Y1512473D01*
X867254D01*
X790919Y1499036D01*
G02X790051I-434J2463D01*
G01X177756Y1607005D01*
Y1607006D01*
G03X176402I-677J-3841D01*
G01X80462Y1590087D01*
X58385Y1574629D01*
X36817Y1559528D01*
X27877Y1557952D01*
X20898D01*
X20000Y1558850D01*
G01Y1568249D02*
X20901Y1569150D01*
X28000D01*
X47676Y1572619D01*
X74455Y1591370D01*
X176657Y1609394D01*
G02X177526I435J-2462D01*
G01X747279Y1508951D01*
G03X748633I677J3841D01*
G01X867834Y1529970D01*
X871441D01*
X872941Y1528470D01*
G01X20000Y1571449D02*
X20899Y1570550D01*
X27877D01*
X47127Y1573944D01*
X73906Y1592695D01*
X176414Y1610773D01*
G02X177769I677J-3841D01*
G01X747524Y1510331D01*
G03X748392I434J2462D01*
G01X867711Y1531370D01*
X871441D01*
X872941Y1532870D01*
G01Y1845793D02*
X871441Y1847293D01*
X867877D01*
X830709Y1853847D01*
X164112Y1736061D01*
X155438Y1737591D01*
X137681Y1750026D01*
G02X136724Y1750983I2237J3194D01*
G01X116424Y1779978D01*
G03X116178Y1780224I-819J-573D01*
G01X105395Y1787773D01*
G03X104995Y1787939I-574J-819D01*
G01X91405Y1790334D01*
G03X91057I-174J-984D01*
G01X91053Y1790333D01*
Y1790335D01*
X85555Y1789363D01*
G03X85295Y1789256I111J-640D01*
G01X83594Y1788066D01*
G03X83434Y1787906I373J-533D01*
G01X79522Y1782318D01*
X70411Y1775938D01*
G03X70165Y1775692I573J-819D01*
G01X65430Y1768929D01*
G03X65322Y1768669I532J-373D01*
G01X47412Y1667088D01*
X32160Y1645302D01*
X27703Y1642183D01*
X24347Y1641591D01*
X20901D01*
X20000Y1640690D01*
G01X872941Y1850193D02*
X871441Y1848693D01*
X868000D01*
X830708Y1855269D01*
X164112Y1737483D01*
X155986Y1738917D01*
X138484Y1751173D01*
G02X137871Y1751787I1436J2047D01*
G01X117572Y1780781D01*
G03X116983Y1781370I-1966J-1377D01*
G01X106199Y1788920D01*
G03X105239Y1789318I-1377J-1965D01*
G01X91648Y1791713D01*
X91645Y1791714D01*
G03X90809I-418J-2363D01*
G01X85313Y1790742D01*
G03X84493Y1790404I353J-2019D01*
G01X82791Y1789213D01*
G03X82287Y1788709I1176J-1680D01*
G01X78516Y1783324D01*
X69608Y1777085D01*
G03X69018Y1776496I1375J-1967D01*
G01X64283Y1769732D01*
G03X63943Y1768912I1679J-1177D01*
G01X46087Y1667637D01*
X31154Y1646308D01*
X27154Y1643508D01*
X24224Y1642991D01*
X20899D01*
X20000Y1643890D01*
G01Y1593496D02*
X20899Y1592597D01*
X28000D01*
X51897Y1596812D01*
X58712Y1595610D01*
X163766Y1614139D01*
G03X164025Y1614247I-114J639D01*
G01X164026D01*
X168866Y1617636D01*
G03X169025Y1617795I-373J532D01*
G01X176059Y1627841D01*
Y1627842D01*
G03X176167Y1628101I-531J374D01*
G01X177077Y1633263D01*
G03Y1633489I-640J113D01*
G01X173319Y1654804D01*
G03X173154Y1655203I-985J-174D01*
G01Y1655204D01*
X132038Y1714054D01*
X131064Y1714227D01*
X129947Y1715826D01*
X130120Y1716800D01*
X129003Y1718399D01*
X128029Y1718572D01*
X126912Y1720171D01*
X127085Y1721145D01*
X125968Y1722744D01*
X124994Y1722917D01*
X123877Y1724516D01*
X124050Y1725490D01*
X122933Y1727089D01*
X121959Y1727262D01*
X120842Y1728861D01*
X121015Y1729836D01*
X118357Y1733640D01*
X118346Y1733641D01*
G02X117950Y1734599I1968J1374D01*
G01X116842Y1740884D01*
X115985Y1741484D01*
X115646Y1743405D01*
X116247Y1744262D01*
X115908Y1746182D01*
X115051Y1746783D01*
X114712Y1748703D01*
X115313Y1749560D01*
X114974Y1751481D01*
X114117Y1752081D01*
X113778Y1754001D01*
X114379Y1754859D01*
X114078Y1756566D01*
G03X113958Y1756979I-1961J-346D01*
G03X113751Y1757356I-1831J-760D01*
G01X110446Y1762075D01*
G03X110166Y1762409I-2048J-1433D01*
G01X109862Y1762713D01*
G03X109528Y1762994I-1770J-1765D01*
G01X106777Y1764920D01*
G03X105778Y1765333I-1432J-2049D01*
G01X105118Y1765450D01*
G03X104761Y1765481I-355J-2021D01*
G01X101000D01*
X99500Y1763981D01*
G01Y1768381D02*
X101000Y1766881D01*
X104761D01*
G02X105362Y1766829I4J-3452D01*
G01X106022Y1766712D01*
G02X107580Y1766067I-678J-3841D01*
G01X110332Y1764141D01*
G02X110853Y1763702I-2243J-3191D01*
G01X111156Y1763399D01*
G02X111593Y1762878I-2758J-2757D01*
G01X114898Y1758159D01*
G02X115252Y1757514I-2771J-1940D01*
G02X115457Y1756809I-3135J-1294D01*
G01X115812Y1754796D01*
G02X115816Y1754773I-638J-123D01*
G01X119325Y1734864D01*
G03X119490Y1734465I985J174D01*
G01X174302Y1656006D01*
G02X174698Y1655048I-1968J-1374D01*
G01X178456Y1633732D01*
G02Y1633020I-2019J-356D01*
G01X177546Y1627858D01*
G02X177206Y1627038I-2019J357D01*
G01X170172Y1616992D01*
G02X169669Y1616489I-1679J1176D01*
G01X164829Y1613100D01*
G02X164010Y1612760I-1177J1678D01*
G01X58712Y1594188D01*
X51897Y1595390D01*
X28123Y1591197D01*
X20901D01*
X20000Y1590296D01*
G01Y1606094D02*
X20898Y1605196D01*
X28246D01*
X60222Y1599554D01*
X162151Y1617528D01*
G03X162411Y1617636I-114J640D01*
G01X166482Y1620487D01*
G03X166641Y1620646I-373J532D01*
G01X172541Y1629072D01*
Y1629073D01*
G03X172649Y1629332I-532J374D01*
G01X173390Y1633535D01*
G03Y1633761I-640J113D01*
G01X169965Y1653187D01*
G03X169800Y1653587I-985J-172D01*
G01X147389Y1685600D01*
X146359Y1685781D01*
X145240Y1687379D01*
X145422Y1688410D01*
X144304Y1690007D01*
G03X144059Y1690252I-819J-574D01*
G01X142462Y1691370D01*
X141431Y1691189D01*
X139834Y1692307D01*
X139652Y1693338D01*
X138055Y1694456D01*
X137024Y1694275D01*
X135427Y1695393D01*
X135245Y1696424D01*
X133648Y1697542D01*
X132617Y1697360D01*
X131020Y1698479D01*
X130838Y1699510D01*
X123222Y1704842D01*
X122094Y1704644D01*
X120611Y1705682D01*
X120412Y1706810D01*
X118815Y1707928D01*
X117784Y1707747D01*
X116187Y1708865D01*
X116005Y1709896D01*
X114408Y1711014D01*
X113377Y1710832D01*
X111780Y1711951D01*
X111598Y1712982D01*
X110001Y1714100D01*
X104402Y1715087D01*
X100999D01*
X99500Y1713588D01*
G01X20000Y1602894D02*
X20902Y1603796D01*
X28123D01*
X60222Y1598132D01*
X162394Y1616149D01*
G03X163214Y1616489I-357J2019D01*
G01X167285Y1619340D01*
G03X167788Y1619843I-1176J1679D01*
G01X173688Y1628269D01*
G03X174028Y1629089I-1679J1177D01*
G01X174769Y1633292D01*
G03Y1634004I-2019J356D01*
G01X171344Y1653430D01*
G03X170947Y1654390I-2364J-415D01*
G01X145452Y1690810D01*
G03X144862Y1691400I-1966J-1376D01*
G01X110550Y1715425D01*
X104525Y1716487D01*
X101001D01*
X99500Y1717988D01*
G01X20000Y1618693D02*
X20899Y1617794D01*
X41012D01*
G02X41368Y1617763I1J-2050D01*
G01X88276Y1609492D01*
X92733Y1610139D01*
X92743Y1610141D01*
X158347Y1621706D01*
G03X158607Y1621814I-113J640D01*
G01X163501Y1625240D01*
G03X163660Y1625399I-373J532D01*
G01X167369Y1630695D01*
G03X167477Y1630955I-532J374D01*
G01X168146Y1634752D01*
G03Y1634978I-640J113D01*
G01X165328Y1650955D01*
G03X165220Y1651215I-640J-113D01*
G01X158427Y1660918D01*
G03X158181Y1661164I-819J-573D01*
G01X156584Y1662283D01*
X155553Y1662101D01*
X153956Y1663219D01*
X153774Y1664250D01*
X152177Y1665368D01*
X151146Y1665187D01*
X149549Y1666305D01*
X149367Y1667336D01*
X149366D01*
X140030Y1673874D01*
X138999Y1673692D01*
X137402Y1674810D01*
X137220Y1675841D01*
X135623Y1676960D01*
X134592Y1676778D01*
X132995Y1677896D01*
X132813Y1678927D01*
X132812D01*
X122678Y1686023D01*
X121704Y1685851D01*
X120106Y1686970D01*
X119934Y1687944D01*
X118337Y1689063D01*
X117362Y1688891D01*
X115765Y1690010D01*
X115593Y1690984D01*
X113996Y1692103D01*
X113021Y1691931D01*
X111424Y1693050D01*
X111252Y1694024D01*
X109243Y1695431D01*
X104941Y1696189D01*
X100999D01*
X99500Y1694690D01*
G01Y1699090D02*
X101001Y1697589D01*
X105064D01*
X109792Y1696756D01*
X158985Y1662311D01*
G02X159574Y1661721I-1378J-1965D01*
G01X166367Y1652018D01*
G02X166707Y1651199I-1679J-1177D01*
G01X169525Y1635221D01*
G02Y1634509I-2019J-356D01*
G01X168856Y1630712D01*
G02X168516Y1629892I-2019J357D01*
G01X164807Y1624596D01*
G02X164304Y1624093I-1679J1176D01*
G01X159410Y1620667D01*
G02X158590Y1620327I-1177J1679D01*
G01X92955Y1608756D01*
X88254Y1608074D01*
X41125Y1616384D01*
X41124D01*
G03X41011Y1616394I-114J-640D01*
G01X20901D01*
X20000Y1615493D01*
G01X99500Y1675792D02*
X101337Y1677629D01*
X102686D01*
G02X102885Y1677609I0J-1000D01*
G01X105743Y1677027D01*
G02X105914Y1676976I-199J-979D01*
G01X106309Y1676818D01*
G02X106469Y1676737I-370J-929D01*
G01Y1676736D01*
X117458Y1669830D01*
X117459D01*
X117679Y1668865D01*
X119330Y1667827D01*
X120295Y1668048D01*
X121946Y1667010D01*
X122167Y1666045D01*
X123818Y1665007D01*
X124783Y1665228D01*
X126434Y1664190D01*
G03X127642Y1663695I2024J3217D01*
G01X127643D01*
X137652Y1661501D01*
X138186Y1660668D01*
X140091Y1660250D01*
X140924Y1660784D01*
X142829Y1660367D01*
X143363Y1659534D01*
X145268Y1659116D01*
X146101Y1659650D01*
X148006Y1659233D01*
X148540Y1658400D01*
X150445Y1657982D01*
X151278Y1658516D01*
X153183Y1658099D01*
G02X153543Y1657941I-214J-977D01*
G01X157255Y1655342D01*
G02X157845Y1654752I-1376J-1966D01*
G01X161497Y1649534D01*
G02X161894Y1648574I-1967J-1375D01*
G01X162347Y1646005D01*
X161780Y1645194D01*
X162118Y1643273D01*
X162929Y1642706D01*
X163268Y1640785D01*
X162700Y1639974D01*
X163039Y1638054D01*
X163850Y1637486D01*
X164189Y1635566D01*
G02X164190Y1634732I-2363J-420D01*
G01X163769Y1632348D01*
G02X163372Y1631390I-2363J418D01*
G01X161422Y1628602D01*
G02X161263Y1628443I-532J373D01*
G01X156653Y1625216D01*
G02X156393Y1625108I-373J532D01*
G01X93943Y1614095D01*
G02X93596I-173J985D01*
G01X76242Y1617154D01*
G02X76106Y1617194I114J639D01*
G01X56556Y1625301D01*
G03X56053Y1625448I-921J-2216D01*
G01X28000Y1630393D01*
X20898D01*
X20000Y1631291D01*
G01X99500Y1680192D02*
X100663Y1679029D01*
X102686D01*
G02X103164Y1678981I0J-2400D01*
G01X106021Y1678400D01*
G02X106434Y1678277I-476J-2352D01*
G01X106831Y1678118D01*
G02X107215Y1677922I-895J-2227D01*
G01X127180Y1665376D01*
G03X127943Y1665063I1279J2031D01*
G01X153483Y1659467D01*
G02X154346Y1659088I-515J-2344D01*
G01X158058Y1656489D01*
G02X158992Y1655555I-2179J-3113D01*
G01X162644Y1650337D01*
G02X163273Y1648817I-3114J-2179D01*
G01X163500Y1647532D01*
X163501D01*
X165568Y1635810D01*
G02X165569Y1634490I-3742J-663D01*
G01X165148Y1632104D01*
G02X164519Y1630587I-3742J663D01*
G01X162569Y1627799D01*
G02X162066Y1627296I-1679J1176D01*
G01X159761Y1625682D01*
X157456Y1624069D01*
G02X156636Y1623729I-1177J1679D01*
G01X94186Y1612716D01*
G02X93352I-417J2364D01*
G01X76000Y1615775D01*
G02X75570Y1615900I354J2019D01*
G01X75569Y1615901D01*
X56020Y1624007D01*
G03X55811Y1624068I-383J-924D01*
G01X55810Y1624069D01*
X27877Y1628993D01*
X20902D01*
X20000Y1628091D01*
G01X144595Y1850193D02*
X143095Y1848693D01*
X139031D01*
X77893Y1837913D01*
G03X76933Y1837516I415J-2364D01*
G01X63395Y1828038D01*
G03X62805Y1827448I1376J-1966D01*
G01X55573Y1817121D01*
X39547Y1726223D01*
X33918Y1718186D01*
X30697Y1715929D01*
X27877Y1715432D01*
X20899D01*
X20000Y1716331D01*
G01X144595Y1845793D02*
X143095Y1847293D01*
X139154D01*
X78136Y1836534D01*
G03X77736Y1836369I172J-985D01*
G01X64198Y1826890D01*
G03X63953Y1826645I574J-819D01*
G01X56898Y1816572D01*
X40872Y1725674D01*
X34924Y1717180D01*
X31246Y1714604D01*
X28000Y1714032D01*
X20901D01*
X20000Y1713131D01*
G01X872941Y1896186D02*
X871440Y1897687D01*
X868198D01*
Y1897686D01*
X863812Y1896913D01*
X859428Y1896141D01*
X795661Y1851492D01*
X164817Y1740246D01*
X156092Y1741785D01*
X140062Y1753006D01*
G02X139104Y1753964I2237J3195D01*
G01X118705Y1783091D01*
G03X118091Y1783705I-2048J-1434D01*
G01X106997Y1791472D01*
G03X105997Y1791886I-1434J-2048D01*
G01X92329Y1794296D01*
G03X91457I-436J-2462D01*
G01X84374Y1793037D01*
G03X83853Y1792884I440J-2461D01*
G01X83361Y1792680D01*
G03X82884Y1792418I958J-2309D01*
G01X81003Y1791100D01*
G03X80391Y1790487I1437J-2046D01*
G01X76634Y1785122D01*
G02X76045Y1784533I-1966J1377D01*
G01X68169Y1779018D01*
G03X67904Y1778796I1152J-1644D01*
G03X67681Y1778531I1404J-1408D01*
G01X61611Y1769860D01*
G03X61476Y1769615I1057J-742D01*
G03X61398Y1769346I1182J-489D01*
G01X45738Y1680563D01*
X38721Y1670542D01*
X35167Y1668053D01*
X28000Y1666789D01*
X20902D01*
X20000Y1665887D01*
G01X872941Y1900586D02*
X871442Y1899087D01*
X868075D01*
X858879Y1897466D01*
X795112Y1852817D01*
X164817Y1741668D01*
X156641Y1743110D01*
X140865Y1754153D01*
G02X140251Y1754767I1434J2048D01*
G01X119852Y1783894D01*
G03X118894Y1784852I-3195J-2237D01*
G01X107800Y1792619D01*
G03X106240Y1793265I-2237J-3195D01*
G01X92573Y1795675D01*
G03X91212I-681J-3841D01*
G01X84128Y1794416D01*
G03X83314Y1794177I685J-3840D01*
G01X83070Y1794075D01*
X82824Y1793974D01*
G03X82080Y1793565I1496J-3602D01*
G01X80199Y1792247D01*
G03X79244Y1791290I2242J-3192D01*
G01X75487Y1785925D01*
G02X75242Y1785680I-819J574D01*
G01X67366Y1780165D01*
G03X66916Y1779788I1955J-2791D01*
G03X66534Y1779335I2390J-2403D01*
G01X60464Y1770664D01*
G03X60183Y1770152I2205J-1543D01*
G03X60019Y1769588I2475J-1026D01*
G01X44438Y1681254D01*
G02X44330Y1680994I-640J113D01*
G01X37781Y1671642D01*
G02X37621Y1671482I-533J373D01*
G01X36166Y1670462D01*
X34618Y1669378D01*
X27877Y1668189D01*
X20898D01*
X20000Y1669087D01*
G01Y1678485D02*
X20901Y1679386D01*
X27941D01*
X32553Y1680199D01*
X40041Y1685442D01*
X43393Y1690233D01*
G03X43501Y1690493I-532J373D01*
G01Y1690492D01*
X60139Y1784839D01*
X60140D01*
G02X60306Y1785240I985J-173D01*
G01Y1785239D01*
X72062Y1802030D01*
X72295Y1802257D01*
X76077Y1804905D01*
X79857Y1807552D01*
G02X80257Y1807718I574J-819D01*
G01X86465Y1808814D01*
G02X86825Y1808812I175J-985D01*
G01X93662Y1807520D01*
G02X94050Y1807357I-184J-982D01*
G01X117936Y1790634D01*
X118169Y1790405D01*
X141533Y1757056D01*
X141536Y1757052D01*
G03X142493Y1756095I3194J2237D01*
G01X157723Y1745432D01*
X164751Y1744193D01*
X769220Y1850808D01*
X861556Y1915449D01*
X868000Y1916585D01*
X871440D01*
X872941Y1915084D01*
G01X20000Y1681685D02*
X20899Y1680786D01*
X27818D01*
X32004Y1681524D01*
X39035Y1686448D01*
X42151Y1690900D01*
X58760Y1785082D01*
G02X59158Y1786042I2363J-417D01*
G01X59159Y1786043D01*
X70993Y1802945D01*
X71399Y1803339D01*
X71491Y1803404D01*
X71492D01*
X79054Y1808699D01*
G02X80014Y1809097I1377J-1965D01*
G01X86222Y1810193D01*
G02X87085Y1810188I418J-2363D01*
G01X93922Y1808897D01*
G02X94853Y1808505I-445J-2358D01*
G01X118835Y1791715D01*
X119243Y1791314D01*
X142680Y1757860D01*
Y1757859D01*
G03X143294Y1757245I2048J1434D01*
G01X143297Y1757243D01*
X158271Y1746758D01*
X164751Y1745615D01*
X768671Y1852133D01*
X861007Y1916774D01*
X867877Y1917985D01*
X871442D01*
X872941Y1919484D01*
G01Y1933982D02*
X871441Y1935482D01*
X867699D01*
X864476Y1934914D01*
X743292Y1850124D01*
X164814Y1748073D01*
X158862Y1749124D01*
X158860Y1749125D01*
X145230Y1758667D01*
X145229D01*
G02X144271Y1759624I2236J3196D01*
G01X109747Y1808916D01*
X94202Y1819799D01*
X94203Y1819800D01*
X94052Y1819882D01*
X93900Y1819965D01*
X93897Y1819967D01*
X93898D01*
X93555Y1820067D01*
X80858Y1822307D01*
X71225Y1820607D01*
X67500Y1818000D01*
X60544Y1808066D01*
X41298Y1698923D01*
X40101Y1697214D01*
X34192Y1693076D01*
X28000Y1691984D01*
X20901D01*
X20000Y1691083D01*
G01X872941Y1938382D02*
X871441Y1936882D01*
X867576D01*
X863927Y1936240D01*
X742742Y1851449D01*
X164815Y1749496D01*
X159409Y1750450D01*
X146033Y1759814D01*
G02X145419Y1760428I1434J2048D01*
G01X110753Y1809922D01*
X94943Y1820991D01*
X94574Y1821194D01*
X94571Y1821196D01*
X94437Y1821269D01*
X93874Y1821433D01*
X80858Y1823729D01*
X70676Y1821933D01*
X66494Y1819006D01*
X59219Y1808615D01*
X39973Y1699474D01*
X39095Y1698220D01*
X33643Y1694401D01*
X27877Y1693384D01*
X20899D01*
X20000Y1694283D01*
G01X144595Y1900586D02*
X143096Y1899087D01*
X139570D01*
X96674Y1891524D01*
X71343Y1873786D01*
X65045Y1864792D01*
X58712Y1855747D01*
X37569Y1735871D01*
X34103Y1730922D01*
X30680Y1728524D01*
X27877Y1728030D01*
X20899D01*
X20000Y1728929D01*
G01X144595Y1896186D02*
X143094Y1897687D01*
X139693D01*
X97223Y1890199D01*
X72349Y1872780D01*
X60037Y1855198D01*
X38894Y1735322D01*
X35109Y1729916D01*
X31229Y1727199D01*
X28000Y1726630D01*
X20901D01*
X20000Y1725729D01*
G01X144595Y1919484D02*
X143096Y1917985D01*
X139031D01*
X105237Y1912026D01*
X82336Y1895992D01*
X55317Y1857404D01*
X36013Y1747879D01*
X32222Y1742467D01*
X30178Y1741035D01*
X27877Y1740629D01*
X20899D01*
X20000Y1741528D01*
G01X144595Y1915084D02*
X143094Y1916585D01*
X139154D01*
X105786Y1910701D01*
X83342Y1894986D01*
X56642Y1856855D01*
X37338Y1747330D01*
X33228Y1741461D01*
X30727Y1739710D01*
X28000Y1739229D01*
X20901D01*
X20000Y1738328D01*
G01X144595Y1938382D02*
X143095Y1936882D01*
X139365D01*
X111220Y1931919D01*
X94983Y1920551D01*
X51880Y1858988D01*
X33996Y1757643D01*
X32173Y1755039D01*
X32172Y1755038D01*
X30162Y1753630D01*
X27877Y1753227D01*
X20899D01*
X20000Y1754126D01*
G01X144595Y1933982D02*
X143095Y1935482D01*
X139488D01*
X111769Y1930594D01*
X95989Y1919545D01*
X53205Y1858439D01*
X35321Y1757094D01*
X33178Y1754032D01*
X30711Y1752305D01*
X28000Y1751827D01*
X20901D01*
X20000Y1750926D01*
M02*
